FILE_TYPE = MACRO_DRAWING;
SET COLOR_WIRE YELLOW;
SET COLOR_PROP ORANGE;
SET COLOR_DOT WHITE;
SET COLOR_ARC YELLOW;
SET COLOR_BODY GREEN;
SET COLOR_NOTE PURPLE;
SET PROP_DISPLAY VALUE;
SET PAGE_NUMBER P29;
FORCEADD OFFPAGE..2
(-6850 2775);
FORCEPROP 2 LAST $XR2 150 
J 0
(-6481 2775);
DISPLAY 0.638298 (-6481 2775);
PAINT MONO (-6481 2775);
FORCEPROP 2 LAST $XR1 81 
J 0
(-6571 2775);
DISPLAY 0.638298 (-6571 2775);
PAINT MONO (-6571 2775);
FORCEPROP 2 LAST $XR0 29 
J 0
(-6661 2775);
DISPLAY 0.638298 (-6661 2775);
PAINT MONO (-6661 2775);
FORCEPROP 2 LAST CDS_LIB standard
J 0
(-6850 2775);
DISPLAY INVISIBLE (-6850 2775);
FORCEPROP 1 LAST OFFPAGE TRUE
J 0
(-6525 2650);
DISPLAY 0.872340 (-6525 2650);
PAINT GREEN (-6525 2650);
DISPLAY INVISIBLE (-6525 2650);
FORCEPROP 1 LAST COMMENT_BODY TRUE
J 0
(-6895 2680);
DISPLAY 0.872340 (-6895 2680);
PAINT PEACH (-6895 2680);
DISPLAY INVISIBLE (-6895 2680);
FORCEPROP 2 LAST PATH I276
J 0
(-6550 2825);
DISPLAY 1.021277 (-6550 2825);
DISPLAY INVISIBLE (-6550 2825);
FORCEADD UNIVERSAL_POWER..1
(-7925 3675);
FORCEPROP 3 LASTPIN (-7925 3625) SIG_NAME PVDD18_S5_P0\g
J 0
(-7915 3635);
DISPLAY 0.659574 (-7915 3635);
PAINT MONO (-7915 3635);
DISPLAY INVISIBLE (-7915 3635);
FORCEPROP 1 LAST HDL_POWER PVDD18_S5_P0
J 1
(-7925 3725);
DISPLAY 0.489362 (-7925 3725);
PAINT GREEN (-7925 3725);
FORCEPROP 2 LAST CDS_LIB pure_quanta_power
J 0
(-7925 3675);
DISPLAY INVISIBLE (-7925 3675);
FORCEPROP 1 LAST PATH I277
J 0
(-7875 3700);
DISPLAY 0.872340 (-7875 3700);
PAINT AQUA (-7875 3700);
DISPLAY INVISIBLE (-7875 3700);
FORCEADD OFFPAGE..2
(-6850 2875);
FORCEPROP 2 LAST $XR2 150 
J 0
(-6481 2875);
DISPLAY 0.638298 (-6481 2875);
PAINT MONO (-6481 2875);
FORCEPROP 2 LAST $XR1 81 
J 0
(-6571 2875);
DISPLAY 0.638298 (-6571 2875);
PAINT MONO (-6571 2875);
FORCEPROP 2 LAST $XR0 29 
J 0
(-6661 2875);
DISPLAY 0.638298 (-6661 2875);
PAINT MONO (-6661 2875);
FORCEPROP 2 LAST CDS_LIB standard
J 0
(-6850 2875);
DISPLAY INVISIBLE (-6850 2875);
FORCEPROP 1 LAST OFFPAGE TRUE
J 0
(-6525 2750);
DISPLAY 0.872340 (-6525 2750);
PAINT GREEN (-6525 2750);
DISPLAY INVISIBLE (-6525 2750);
FORCEPROP 1 LAST COMMENT_BODY TRUE
J 0
(-6895 2780);
DISPLAY 0.872340 (-6895 2780);
PAINT PEACH (-6895 2780);
DISPLAY INVISIBLE (-6895 2780);
FORCEPROP 2 LAST PATH I280
J 0
(-6550 2925);
DISPLAY 1.021277 (-6550 2925);
DISPLAY INVISIBLE (-6550 2925);
FORCEADD Q_RES..2
(-7925 3225);
FORCEPROP 1 LAST LOCATION R457
J 0
(-7880 3350);
DISPLAY 0.489362 (-7880 3350);
PAINT SKYBLUE (-7880 3350);
FORCEPROP 0 LAST $SEC 1
J 0
(-7875 3400);
DISPLAY 0.680851 (-7875 3400);
PAINT MONO (-7875 3400);
DISPLAY INVISIBLE (-7875 3400);
FORCEPROP 0 LAST CDS_SEC 1
J 0
(-7875 3400);
DISPLAY 1.021277 (-7875 3400);
DISPLAY INVISIBLE (-7875 3400);
FORCEPROP 1 LASTPIN (-7925 3325) $PN 1
J 0
(-7920 3287);
DISPLAY 0.489362 (-7920 3287);
PAINT MONO (-7920 3287);
FORCEPROP 1 LASTPIN (-7925 3125) $PN 2
J 0
(-7920 3135);
DISPLAY 0.489362 (-7920 3135);
PAINT MONO (-7920 3135);
FORCEPROP 1 LAST TOLERANCE 5%
J 0
(-7880 3250);
DISPLAY 0.489362 (-7880 3250);
PAINT SKYBLUE (-7880 3250);
FORCEPROP 1 LAST MATERIAL EMPTY
J 0
(-7885 3150);
DISPLAY 0.489362 (-7885 3150);
PAINT SKYBLUE (-7885 3150);
FORCEPROP 1 LAST VALUE 4.7K
J 0
(-7880 3300);
DISPLAY 0.489362 (-7880 3300);
PAINT SKYBLUE (-7880 3300);
FORCEPROP 1 LAST WATTAGE 1/16W
J 0
(-7885 3200);
DISPLAY 0.489362 (-7885 3200);
PAINT SKYBLUE (-7885 3200);
FORCEPROP 1 LAST PACK_TYPE 0402LF
J 0
(-7875 3100);
DISPLAY 0.489362 (-7875 3100);
PAINT SKYBLUE (-7875 3100);
FORCEPROP 2 LAST CDS_LIB pure_quanta
J 0
(-7925 3225);
DISPLAY INVISIBLE (-7925 3225);
FORCEPROP 1 LAST PATH I282
J 0
(-7875 3400);
DISPLAY 0.978723 (-7875 3400);
PAINT WHITE (-7875 3400);
DISPLAY INVISIBLE (-7875 3400);
FORCEPROP 1 LAST PART_NUMBER CS24702JB10
J 0
(-7885 3100);
DISPLAY 0.489362 (-7885 3100);
PAINT SKYBLUE (-7885 3100);
DISPLAY INVISIBLE (-7885 3100);
FORCEADD Q_RES..2
(-8150 3250);
FORCEPROP 1 LAST LOCATION R455
J 0
(-8105 3375);
DISPLAY 0.489362 (-8105 3375);
PAINT SKYBLUE (-8105 3375);
FORCEPROP 0 LAST $SEC 1
J 0
(-8100 3425);
DISPLAY 0.680851 (-8100 3425);
PAINT MONO (-8100 3425);
DISPLAY INVISIBLE (-8100 3425);
FORCEPROP 0 LAST CDS_SEC 1
J 0
(-8100 3425);
DISPLAY 1.021277 (-8100 3425);
DISPLAY INVISIBLE (-8100 3425);
FORCEPROP 1 LASTPIN (-8150 3350) $PN 1
J 0
(-8145 3312);
DISPLAY 0.489362 (-8145 3312);
PAINT MONO (-8145 3312);
FORCEPROP 1 LASTPIN (-8150 3150) $PN 2
J 0
(-8145 3160);
DISPLAY 0.489362 (-8145 3160);
PAINT MONO (-8145 3160);
FORCEPROP 1 LAST MATERIAL EMPTY
J 0
(-8110 3175);
DISPLAY 0.489362 (-8110 3175);
PAINT SKYBLUE (-8110 3175);
FORCEPROP 1 LAST VALUE 4.7K
J 0
(-8105 3325);
DISPLAY 0.489362 (-8105 3325);
PAINT SKYBLUE (-8105 3325);
FORCEPROP 1 LAST PACK_TYPE 0402LF
J 0
(-8100 3125);
DISPLAY 0.489362 (-8100 3125);
PAINT SKYBLUE (-8100 3125);
FORCEPROP 1 LAST WATTAGE 1/16W
J 0
(-8110 3225);
DISPLAY 0.489362 (-8110 3225);
PAINT SKYBLUE (-8110 3225);
FORCEPROP 1 LAST TOLERANCE 5%
J 0
(-8105 3275);
DISPLAY 0.489362 (-8105 3275);
PAINT SKYBLUE (-8105 3275);
FORCEPROP 2 LAST CDS_LIB pure_quanta
J 0
(-8150 3250);
DISPLAY INVISIBLE (-8150 3250);
FORCEPROP 1 LAST PATH I284
J 0
(-8100 3425);
DISPLAY 0.978723 (-8100 3425);
PAINT WHITE (-8100 3425);
DISPLAY INVISIBLE (-8100 3425);
FORCEPROP 1 LAST PART_NUMBER CS24702JB10
J 0
(-8110 3125);
DISPLAY 0.489362 (-8110 3125);
PAINT SKYBLUE (-8110 3125);
DISPLAY INVISIBLE (-8110 3125);
FORCEADD GENOA_SP5..22
(-4675 4825);
FORCEPROP 1 LAST LOCATION U25
J 0
(-5770 6356);
DISPLAY 0.489362 (-5770 6356);
PAINT SKYBLUE (-5770 6356);
FORCEPROP 0 LAST $SEC 22
J 0
(-5750 6400);
DISPLAY 0.680851 (-5750 6400);
PAINT MONO (-5750 6400);
DISPLAY INVISIBLE (-5750 6400);
FORCEPROP 0 LAST CDS_SEC 22
J 0
(-5775 6400);
DISPLAY 1.021277 (-5775 6400);
DISPLAY INVISIBLE (-5775 6400);
FORCEPROP 0 LASTPIN (-5925 4250) $PN DJ25
J 2
(-5935 4260);
DISPLAY 0.489362 (-5935 4260);
PAINT MONO (-5935 4260);
FORCEPROP 0 LASTPIN (-5925 4500) $PN DJ22
J 2
(-5935 4510);
DISPLAY 0.489362 (-5935 4510);
PAINT MONO (-5935 4510);
FORCEPROP 0 LASTPIN (-5925 5250) $PN DF28
J 2
(-5935 5260);
DISPLAY 0.489362 (-5935 5260);
PAINT MONO (-5935 5260);
FORCEPROP 0 LASTPIN (-5925 5200) $PN DG22
J 2
(-5935 5210);
DISPLAY 0.489362 (-5935 5210);
PAINT MONO (-5935 5210);
FORCEPROP 0 LASTPIN (-5925 5150) $PN DJ28
J 2
(-5935 5160);
DISPLAY 0.489362 (-5935 5160);
PAINT MONO (-5935 5160);
FORCEPROP 0 LASTPIN (-5925 5100) $PN DG29
J 2
(-5935 5110);
DISPLAY 0.489362 (-5935 5110);
PAINT MONO (-5935 5110);
FORCEPROP 0 LASTPIN (-5925 4650) $PN DF24
J 2
(-5935 4660);
DISPLAY 0.489362 (-5935 4660);
PAINT MONO (-5935 4660);
FORCEPROP 0 LASTPIN (-5925 4950) $PN DH24
J 2
(-5935 4960);
DISPLAY 0.489362 (-5935 4960);
PAINT MONO (-5935 4960);
FORCEPROP 0 LASTPIN (-5925 4900) $PN DE24
J 2
(-5935 4910);
DISPLAY 0.489362 (-5935 4910);
PAINT MONO (-5935 4910);
FORCEPROP 0 LASTPIN (-5925 4850) $PN DF25
J 2
(-5935 4860);
DISPLAY 0.489362 (-5935 4860);
PAINT MONO (-5935 4860);
FORCEPROP 0 LASTPIN (-5925 4800) $PN DG25
J 2
(-5935 4810);
DISPLAY 0.489362 (-5935 4810);
PAINT MONO (-5935 4810);
FORCEPROP 0 LASTPIN (-5925 5650) $PN DJ27
J 2
(-5935 5660);
DISPLAY 0.489362 (-5935 5660);
PAINT MONO (-5935 5660);
FORCEPROP 0 LASTPIN (-5925 4450) $PN DG23
J 2
(-5935 4460);
DISPLAY 0.489362 (-5935 4460);
PAINT MONO (-5935 4460);
FORCEPROP 0 LASTPIN (-5925 4400) $PN DF27
J 2
(-5935 4410);
DISPLAY 0.489362 (-5935 4410);
PAINT MONO (-5935 4410);
FORCEPROP 0 LASTPIN (-5925 5600) $PN DG28
J 2
(-5935 5610);
DISPLAY 0.489362 (-5935 5610);
PAINT MONO (-5935 5610);
FORCEPROP 0 LASTPIN (-5925 5550) $PN DJ23
J 2
(-5935 5560);
DISPLAY 0.489362 (-5935 5560);
PAINT MONO (-5935 5560);
FORCEPROP 0 LASTPIN (-5925 5450) $PN DJ26
J 2
(-5935 5460);
DISPLAY 0.489362 (-5935 5460);
PAINT MONO (-5935 5460);
FORCEPROP 0 LASTPIN (-5925 4350) $PN DE27
J 2
(-5935 4360);
DISPLAY 0.489362 (-5935 4360);
PAINT MONO (-5935 4360);
FORCEPROP 0 LASTPIN (-5925 5900) $PN DF30
J 2
(-5935 5910);
DISPLAY 0.489362 (-5935 5910);
PAINT MONO (-5935 5910);
FORCEPROP 0 LASTPIN (-5925 5850) $PN DG26
J 2
(-5935 5860);
DISPLAY 0.489362 (-5935 5860);
PAINT MONO (-5935 5860);
FORCEPROP 0 LASTPIN (-5925 5800) $PN DH27
J 2
(-5935 5810);
DISPLAY 0.489362 (-5935 5810);
PAINT MONO (-5935 5810);
FORCEPROP 0 LASTPIN (-3425 5850) $PN A25
J 0
(-3415 5860);
DISPLAY 0.489362 (-3415 5860);
PAINT MONO (-3415 5860);
FORCEPROP 0 LASTPIN (-3425 5900) $PN A26
J 0
(-3415 5910);
DISPLAY 0.489362 (-3415 5910);
PAINT MONO (-3415 5910);
FORCEPROP 0 LASTPIN (-3425 3950) $PN E23
J 0
(-3415 3960);
DISPLAY 0.489362 (-3415 3960);
PAINT MONO (-3415 3960);
FORCEPROP 0 LASTPIN (-3425 5200) $PN E26
J 0
(-3415 5210);
DISPLAY 0.489362 (-3415 5210);
PAINT MONO (-3415 5210);
FORCEPROP 0 LASTPIN (-3425 5250) $PN E27
J 0
(-3415 5260);
DISPLAY 0.489362 (-3415 5260);
PAINT MONO (-3415 5260);
FORCEPROP 0 LASTPIN (-3425 4550) $PN C26
J 0
(-3415 4560);
DISPLAY 0.489362 (-3415 4560);
PAINT MONO (-3415 4560);
FORCEPROP 0 LASTPIN (-3425 4600) $PN C25
J 0
(-3415 4610);
DISPLAY 0.489362 (-3415 4610);
PAINT MONO (-3415 4610);
FORCEPROP 0 LASTPIN (-3425 5700) $PN A29
J 0
(-3415 5710);
DISPLAY 0.489362 (-3415 5710);
PAINT MONO (-3415 5710);
FORCEPROP 0 LASTPIN (-3425 5750) $PN A28
J 0
(-3415 5760);
DISPLAY 0.489362 (-3415 5760);
PAINT MONO (-3415 5760);
FORCEPROP 0 LASTPIN (-3425 3900) $PN E24
J 0
(-3415 3910);
DISPLAY 0.489362 (-3415 3910);
PAINT MONO (-3415 3910);
FORCEPROP 0 LASTPIN (-3425 5050) $PN C28
J 0
(-3415 5060);
DISPLAY 0.489362 (-3415 5060);
PAINT MONO (-3415 5060);
FORCEPROP 0 LASTPIN (-3425 5100) $PN C29
J 0
(-3415 5110);
DISPLAY 0.489362 (-3415 5110);
PAINT MONO (-3415 5110);
FORCEPROP 0 LASTPIN (-3425 4400) $PN E29
J 0
(-3415 4410);
DISPLAY 0.489362 (-3415 4410);
PAINT MONO (-3415 4410);
FORCEPROP 0 LASTPIN (-3425 4450) $PN E30
J 0
(-3415 4460);
DISPLAY 0.489362 (-3415 4460);
PAINT MONO (-3415 4460);
FORCEPROP 0 LASTPIN (-3425 5550) $PN DH67
J 0
(-3415 5560);
DISPLAY 0.489362 (-3415 5560);
PAINT MONO (-3415 5560);
FORCEPROP 0 LASTPIN (-3425 5600) $PN DJ67
J 0
(-3415 5610);
DISPLAY 0.489362 (-3415 5610);
PAINT MONO (-3415 5610);
FORCEPROP 0 LASTPIN (-3425 3850) $PN DG40
J 0
(-3415 3860);
DISPLAY 0.489362 (-3415 3860);
PAINT MONO (-3415 3860);
FORCEPROP 0 LASTPIN (-3425 4900) $PN DH65
J 0
(-3415 4910);
DISPLAY 0.489362 (-3415 4910);
PAINT MONO (-3415 4910);
FORCEPROP 0 LASTPIN (-3425 4950) $PN DJ65
J 0
(-3415 4960);
DISPLAY 0.489362 (-3415 4960);
PAINT MONO (-3415 4960);
FORCEPROP 0 LASTPIN (-3425 4250) $PN DJ69
J 0
(-3415 4260);
DISPLAY 0.489362 (-3415 4260);
PAINT MONO (-3415 4260);
FORCEPROP 0 LASTPIN (-3425 4300) $PN DH69
J 0
(-3415 4310);
DISPLAY 0.489362 (-3415 4310);
PAINT MONO (-3415 4310);
FORCEPROP 0 LASTPIN (-3425 5400) $PN DJ60
J 0
(-3415 5410);
DISPLAY 0.489362 (-3415 5410);
PAINT MONO (-3415 5410);
FORCEPROP 0 LASTPIN (-3425 5450) $PN DH60
J 0
(-3415 5460);
DISPLAY 0.489362 (-3415 5460);
PAINT MONO (-3415 5460);
FORCEPROP 0 LASTPIN (-3425 3800) $PN DH40
J 0
(-3415 3810);
DISPLAY 0.489362 (-3415 3810);
PAINT MONO (-3415 3810);
FORCEPROP 0 LASTPIN (-3425 4750) $PN DH62
J 0
(-3415 4760);
DISPLAY 0.489362 (-3415 4760);
PAINT MONO (-3415 4760);
FORCEPROP 0 LASTPIN (-3425 4800) $PN DJ62
J 0
(-3415 4810);
DISPLAY 0.489362 (-3415 4810);
PAINT MONO (-3415 4810);
FORCEPROP 0 LASTPIN (-3425 4100) $PN DH58
J 0
(-3415 4110);
DISPLAY 0.489362 (-3415 4110);
PAINT MONO (-3415 4110);
FORCEPROP 0 LASTPIN (-3425 4150) $PN DG58
J 0
(-3415 4160);
DISPLAY 0.489362 (-3415 4160);
PAINT MONO (-3415 4160);
FORCEPROP 1 LAST MATERIAL IO
J 0
(-5770 6082);
DISPLAY 0.489362 (-5770 6082);
PAINT SKYBLUE (-5770 6082);
FORCEPROP 2 LAST VALUE SOCKET6096_13568-001
J 0
(-5775 6228);
DISPLAY 0.489362 (-5775 6228);
PAINT SKYBLUE (-5775 6228);
FORCEPROP 2 LAST PART_TYPE SMLF
J 0
(-5775 6275);
DISPLAY 1.021277 (-5775 6275);
FORCEPROP 1 LAST NEEDS_NO_SIZE TRUE
J 0
(-4675 4825);
DISPLAY 0.723404 (-4675 4825);
PAINT GREEN (-4675 4825);
DISPLAY INVISIBLE (-4675 4825);
FORCEPROP 1 LAST CDS_LMAN_SYM_OUTLINE -1100,1225,1100,-1225
J 0
(-4675 4825);
DISPLAY 0.468085 (-4675 4825);
PAINT GREEN (-4675 4825);
DISPLAY INVISIBLE (-4675 4825);
FORCEPROP 2 LAST CDS_LIB pure_quanta
J 0
(-4675 4825);
DISPLAY INVISIBLE (-4675 4825);
FORCEPROP 1 LAST PATH I287
J 0
(-4675 4825);
DISPLAY 0.723404 (-4675 4825);
PAINT GREEN (-4675 4825);
DISPLAY INVISIBLE (-4675 4825);
FORCEPROP 1 LAST PART_NUMBER DGA^6000030
J 0
(-5775 6150);
DISPLAY 0.489362 (-5775 6150);
PAINT SKYBLUE (-5775 6150);
DISPLAY INVISIBLE (-5775 6150);
FORCEADD Q_RES..1
(-6950 4850);
FORCEPROP 1 LAST LOCATION R470
J 0
(-6825 4850);
DISPLAY 0.489362 (-6825 4850);
PAINT SKYBLUE (-6825 4850);
FORCEPROP 0 LAST $SEC 1
J 0
(-6825 4875);
DISPLAY 0.680851 (-6825 4875);
PAINT MONO (-6825 4875);
DISPLAY INVISIBLE (-6825 4875);
FORCEPROP 0 LAST CDS_SEC 1
J 0
(-6825 4875);
DISPLAY 1.021277 (-6825 4875);
DISPLAY INVISIBLE (-6825 4875);
FORCEPROP 1 LASTPIN (-7050 4850) $PN 1
J 0
(-7038 4862);
DISPLAY 0.489362 (-7038 4862);
PAINT MONO (-7038 4862);
FORCEPROP 1 LASTPIN (-6850 4850) $PN 2
J 0
(-6888 4862);
DISPLAY 0.489362 (-6888 4862);
PAINT MONO (-6888 4862);
FORCEPROP 1 LAST VALUE 33
J 2
(-7050 4850);
DISPLAY 0.489362 (-7050 4850);
PAINT SKYBLUE (-7050 4850);
FORCEPROP 1 LAST PACK_TYPE 0402LF
J 0
(-6900 4775);
DISPLAY 0.489362 (-6900 4775);
PAINT SKYBLUE (-6900 4775);
DISPLAY INVISIBLE (-6900 4775);
FORCEPROP 1 LAST TOLERANCE 5%
J 0
(-6975 4775);
DISPLAY 0.489362 (-6975 4775);
PAINT SKYBLUE (-6975 4775);
DISPLAY INVISIBLE (-6975 4775);
FORCEPROP 1 LAST MATERIAL CHIP
J 0
(-6525 4775);
DISPLAY 0.489362 (-6525 4775);
PAINT SKYBLUE (-6525 4775);
DISPLAY INVISIBLE (-6525 4775);
FORCEPROP 1 LAST WATTAGE 1/16W
J 2
(-6550 4775);
DISPLAY 0.489362 (-6550 4775);
PAINT SKYBLUE (-6550 4775);
DISPLAY INVISIBLE (-6550 4775);
FORCEPROP 2 LAST CDS_LIB pure_quanta
J 0
(-6950 4850);
DISPLAY INVISIBLE (-6950 4850);
FORCEPROP 1 LAST PATH I327
J 0
(-7000 5000);
DISPLAY 0.978723 (-7000 5000);
PAINT WHITE (-7000 5000);
DISPLAY INVISIBLE (-7000 5000);
FORCEPROP 1 LAST PART_NUMBER CS03302JB10
J 0
(-6925 4900);
DISPLAY 0.489362 (-6925 4900);
PAINT SKYBLUE (-6925 4900);
DISPLAY INVISIBLE (-6925 4900);
FORCEADD Q_RES..1
(-6950 4900);
FORCEPROP 1 LAST LOCATION R469
J 0
(-6825 4900);
DISPLAY 0.489362 (-6825 4900);
PAINT SKYBLUE (-6825 4900);
FORCEPROP 0 LAST $SEC 1
J 0
(-6825 4925);
DISPLAY 0.680851 (-6825 4925);
PAINT MONO (-6825 4925);
DISPLAY INVISIBLE (-6825 4925);
FORCEPROP 0 LAST CDS_SEC 1
J 0
(-6825 4925);
DISPLAY 1.021277 (-6825 4925);
DISPLAY INVISIBLE (-6825 4925);
FORCEPROP 1 LASTPIN (-7050 4900) $PN 1
J 0
(-7038 4912);
DISPLAY 0.489362 (-7038 4912);
PAINT MONO (-7038 4912);
FORCEPROP 1 LASTPIN (-6850 4900) $PN 2
J 0
(-6888 4912);
DISPLAY 0.489362 (-6888 4912);
PAINT MONO (-6888 4912);
FORCEPROP 1 LAST VALUE 33
J 2
(-7050 4900);
DISPLAY 0.489362 (-7050 4900);
PAINT SKYBLUE (-7050 4900);
FORCEPROP 1 LAST PACK_TYPE 0402LF
J 0
(-6900 4825);
DISPLAY 0.489362 (-6900 4825);
PAINT SKYBLUE (-6900 4825);
DISPLAY INVISIBLE (-6900 4825);
FORCEPROP 1 LAST TOLERANCE 5%
J 0
(-6975 4825);
DISPLAY 0.489362 (-6975 4825);
PAINT SKYBLUE (-6975 4825);
DISPLAY INVISIBLE (-6975 4825);
FORCEPROP 1 LAST MATERIAL CHIP
J 0
(-6525 4825);
DISPLAY 0.489362 (-6525 4825);
PAINT SKYBLUE (-6525 4825);
DISPLAY INVISIBLE (-6525 4825);
FORCEPROP 1 LAST WATTAGE 1/16W
J 2
(-6550 4825);
DISPLAY 0.489362 (-6550 4825);
PAINT SKYBLUE (-6550 4825);
DISPLAY INVISIBLE (-6550 4825);
FORCEPROP 2 LAST CDS_LIB pure_quanta
J 0
(-6950 4900);
DISPLAY INVISIBLE (-6950 4900);
FORCEPROP 1 LAST PATH I328
J 0
(-7000 5050);
DISPLAY 0.978723 (-7000 5050);
PAINT WHITE (-7000 5050);
DISPLAY INVISIBLE (-7000 5050);
FORCEPROP 1 LAST PART_NUMBER CS03302JB10
J 0
(-6925 4950);
DISPLAY 0.489362 (-6925 4950);
PAINT SKYBLUE (-6925 4950);
DISPLAY INVISIBLE (-6925 4950);
FORCEADD Q_RES..1
(-6950 4950);
FORCEPROP 1 LAST LOCATION R468
J 0
(-6825 4950);
DISPLAY 0.489362 (-6825 4950);
PAINT SKYBLUE (-6825 4950);
FORCEPROP 0 LAST $SEC 1
J 0
(-6825 4975);
DISPLAY 0.680851 (-6825 4975);
PAINT MONO (-6825 4975);
DISPLAY INVISIBLE (-6825 4975);
FORCEPROP 0 LAST CDS_SEC 1
J 0
(-6825 4975);
DISPLAY 1.021277 (-6825 4975);
DISPLAY INVISIBLE (-6825 4975);
FORCEPROP 1 LASTPIN (-7050 4950) $PN 1
J 0
(-7038 4962);
DISPLAY 0.489362 (-7038 4962);
PAINT MONO (-7038 4962);
FORCEPROP 1 LASTPIN (-6850 4950) $PN 2
J 0
(-6888 4962);
DISPLAY 0.489362 (-6888 4962);
PAINT MONO (-6888 4962);
FORCEPROP 1 LAST VALUE 33
J 2
(-7050 4950);
DISPLAY 0.489362 (-7050 4950);
PAINT SKYBLUE (-7050 4950);
FORCEPROP 1 LAST PACK_TYPE 0402LF
J 0
(-6900 4875);
DISPLAY 0.489362 (-6900 4875);
PAINT SKYBLUE (-6900 4875);
DISPLAY INVISIBLE (-6900 4875);
FORCEPROP 1 LAST TOLERANCE 5%
J 0
(-6975 4875);
DISPLAY 0.489362 (-6975 4875);
PAINT SKYBLUE (-6975 4875);
DISPLAY INVISIBLE (-6975 4875);
FORCEPROP 1 LAST MATERIAL CHIP
J 0
(-6525 4875);
DISPLAY 0.489362 (-6525 4875);
PAINT SKYBLUE (-6525 4875);
DISPLAY INVISIBLE (-6525 4875);
FORCEPROP 1 LAST WATTAGE 1/16W
J 2
(-6550 4875);
DISPLAY 0.489362 (-6550 4875);
PAINT SKYBLUE (-6550 4875);
DISPLAY INVISIBLE (-6550 4875);
FORCEPROP 2 LAST CDS_LIB pure_quanta
J 0
(-6950 4950);
DISPLAY INVISIBLE (-6950 4950);
FORCEPROP 1 LAST PATH I329
J 0
(-7000 5100);
DISPLAY 0.978723 (-7000 5100);
PAINT WHITE (-7000 5100);
DISPLAY INVISIBLE (-7000 5100);
FORCEPROP 1 LAST PART_NUMBER CS03302JB10
J 0
(-6925 5000);
DISPLAY 0.489362 (-6925 5000);
PAINT SKYBLUE (-6925 5000);
DISPLAY INVISIBLE (-6925 5000);
FORCEADD Q_RES..1
(-6950 4800);
FORCEPROP 1 LAST LOCATION R471
J 0
(-6825 4800);
DISPLAY 0.489362 (-6825 4800);
PAINT SKYBLUE (-6825 4800);
FORCEPROP 0 LAST $SEC 1
J 0
(-6825 4825);
DISPLAY 0.680851 (-6825 4825);
PAINT MONO (-6825 4825);
DISPLAY INVISIBLE (-6825 4825);
FORCEPROP 0 LAST CDS_SEC 1
J 0
(-6825 4825);
DISPLAY 1.021277 (-6825 4825);
DISPLAY INVISIBLE (-6825 4825);
FORCEPROP 1 LASTPIN (-7050 4800) $PN 1
J 0
(-7038 4812);
DISPLAY 0.489362 (-7038 4812);
PAINT MONO (-7038 4812);
FORCEPROP 1 LASTPIN (-6850 4800) $PN 2
J 0
(-6888 4812);
DISPLAY 0.489362 (-6888 4812);
PAINT MONO (-6888 4812);
FORCEPROP 1 LAST VALUE 33
J 2
(-7050 4800);
DISPLAY 0.489362 (-7050 4800);
PAINT SKYBLUE (-7050 4800);
FORCEPROP 1 LAST PACK_TYPE 0402LF
J 0
(-6900 4725);
DISPLAY 0.489362 (-6900 4725);
PAINT SKYBLUE (-6900 4725);
DISPLAY INVISIBLE (-6900 4725);
FORCEPROP 1 LAST TOLERANCE 5%
J 0
(-6975 4725);
DISPLAY 0.489362 (-6975 4725);
PAINT SKYBLUE (-6975 4725);
DISPLAY INVISIBLE (-6975 4725);
FORCEPROP 1 LAST MATERIAL CHIP
J 0
(-6525 4725);
DISPLAY 0.489362 (-6525 4725);
PAINT SKYBLUE (-6525 4725);
DISPLAY INVISIBLE (-6525 4725);
FORCEPROP 1 LAST WATTAGE 1/16W
J 2
(-6550 4725);
DISPLAY 0.489362 (-6550 4725);
PAINT SKYBLUE (-6550 4725);
DISPLAY INVISIBLE (-6550 4725);
FORCEPROP 2 LAST CDS_LIB pure_quanta
J 0
(-6950 4800);
DISPLAY INVISIBLE (-6950 4800);
FORCEPROP 1 LAST PATH I330
J 0
(-7000 4950);
DISPLAY 0.978723 (-7000 4950);
PAINT WHITE (-7000 4950);
DISPLAY INVISIBLE (-7000 4950);
FORCEPROP 1 LAST PART_NUMBER CS03302JB10
J 0
(-6925 4850);
DISPLAY 0.489362 (-6925 4850);
PAINT SKYBLUE (-6925 4850);
DISPLAY INVISIBLE (-6925 4850);
FORCEADD Q_RES..1
(-6950 4350);
FORCEPROP 1 LAST LOCATION R474
J 0
(-6825 4350);
DISPLAY 0.489362 (-6825 4350);
PAINT SKYBLUE (-6825 4350);
FORCEPROP 0 LAST $SEC 1
J 0
(-6825 4375);
DISPLAY 0.680851 (-6825 4375);
PAINT MONO (-6825 4375);
DISPLAY INVISIBLE (-6825 4375);
FORCEPROP 0 LAST CDS_SEC 1
J 0
(-6825 4375);
DISPLAY 1.021277 (-6825 4375);
DISPLAY INVISIBLE (-6825 4375);
FORCEPROP 1 LASTPIN (-7050 4350) $PN 1
J 0
(-7038 4362);
DISPLAY 0.489362 (-7038 4362);
PAINT MONO (-7038 4362);
FORCEPROP 1 LASTPIN (-6850 4350) $PN 2
J 0
(-6888 4362);
DISPLAY 0.489362 (-6888 4362);
PAINT MONO (-6888 4362);
FORCEPROP 1 LAST VALUE 0
J 2
(-7050 4350);
DISPLAY 0.489362 (-7050 4350);
PAINT SKYBLUE (-7050 4350);
FORCEPROP 2 LAST CDS_LIB pure_quanta
J 0
(-6950 4350);
DISPLAY INVISIBLE (-6950 4350);
FORCEPROP 1 LAST WATTAGE 1/16W
J 2
(-6550 4275);
DISPLAY 0.489362 (-6550 4275);
PAINT SKYBLUE (-6550 4275);
DISPLAY INVISIBLE (-6550 4275);
FORCEPROP 1 LAST MATERIAL CHIP
J 0
(-6525 4275);
DISPLAY 0.489362 (-6525 4275);
PAINT SKYBLUE (-6525 4275);
DISPLAY INVISIBLE (-6525 4275);
FORCEPROP 1 LAST TOLERANCE 5%
J 0
(-6975 4275);
DISPLAY 0.489362 (-6975 4275);
PAINT SKYBLUE (-6975 4275);
DISPLAY INVISIBLE (-6975 4275);
FORCEPROP 1 LAST PACK_TYPE 0402LF
J 0
(-6900 4275);
DISPLAY 0.489362 (-6900 4275);
PAINT SKYBLUE (-6900 4275);
DISPLAY INVISIBLE (-6900 4275);
FORCEPROP 1 LAST PATH I332
J 0
(-7000 4500);
DISPLAY 0.978723 (-7000 4500);
PAINT WHITE (-7000 4500);
DISPLAY INVISIBLE (-7000 4500);
FORCEPROP 1 LAST PART_NUMBER CS00002JB13
J 0
(-6925 4400);
DISPLAY 0.489362 (-6925 4400);
PAINT SKYBLUE (-6925 4400);
DISPLAY INVISIBLE (-6925 4400);
FORCEADD OFFPAGE..2
R 2
(-7775 5900);
FORCEPROP 2 LAST $XR0 77 
J 0
(-7999 5900);
DISPLAY 0.638298 (-7999 5900);
PAINT MONO (-7999 5900);
FORCEPROP 2 LAST CDS_LIB standard
J 0
(-7775 5900);
DISPLAY INVISIBLE (-7775 5900);
FORCEPROP 1 LAST OFFPAGE TRUE
J 2
(-8100 5775);
DISPLAY 0.872340 (-8100 5775);
PAINT GREEN (-8100 5775);
DISPLAY INVISIBLE (-8100 5775);
FORCEPROP 1 LAST COMMENT_BODY TRUE
J 2
(-7730 5805);
DISPLAY 0.872340 (-7730 5805);
PAINT PEACH (-7730 5805);
DISPLAY INVISIBLE (-7730 5805);
FORCEPROP 2 LAST PATH I335
J 0
(-8025 5950);
DISPLAY 1.021277 (-8025 5950);
DISPLAY INVISIBLE (-8025 5950);
FORCEADD OFFPAGE..2
R 2
(-7775 5850);
FORCEPROP 2 LAST $XR0 77 
J 0
(-7999 5850);
DISPLAY 0.638298 (-7999 5850);
PAINT MONO (-7999 5850);
FORCEPROP 2 LAST CDS_LIB standard
J 0
(-7775 5850);
DISPLAY INVISIBLE (-7775 5850);
FORCEPROP 1 LAST OFFPAGE TRUE
J 2
(-8100 5725);
DISPLAY 0.872340 (-8100 5725);
PAINT GREEN (-8100 5725);
DISPLAY INVISIBLE (-8100 5725);
FORCEPROP 1 LAST COMMENT_BODY TRUE
J 2
(-7730 5755);
DISPLAY 0.872340 (-7730 5755);
PAINT PEACH (-7730 5755);
DISPLAY INVISIBLE (-7730 5755);
FORCEPROP 2 LAST PATH I336
J 0
(-8025 5900);
DISPLAY 1.021277 (-8025 5900);
DISPLAY INVISIBLE (-8025 5900);
FORCEADD OFFPAGE..2
R 2
(-7775 5650);
FORCEPROP 2 LAST $XR1 77 
J 0
(-8089 5650);
DISPLAY 0.638298 (-8089 5650);
PAINT MONO (-8089 5650);
FORCEPROP 2 LAST $XR0 76 
J 0
(-7999 5650);
DISPLAY 0.638298 (-7999 5650);
PAINT MONO (-7999 5650);
FORCEPROP 2 LAST CDS_LIB standard
J 2
(-7775 5650);
DISPLAY INVISIBLE (-7775 5650);
FORCEPROP 1 LAST OFFPAGE TRUE
J 2
(-8100 5525);
DISPLAY 0.872340 (-8100 5525);
PAINT GREEN (-8100 5525);
DISPLAY INVISIBLE (-8100 5525);
FORCEPROP 1 LAST COMMENT_BODY TRUE
J 2
(-7730 5555);
DISPLAY 0.872340 (-7730 5555);
PAINT PEACH (-7730 5555);
DISPLAY INVISIBLE (-7730 5555);
FORCEPROP 2 LAST PATH I337
J 0
(-8025 5700);
DISPLAY 1.021277 (-8025 5700);
DISPLAY INVISIBLE (-8025 5700);
FORCEADD OFFPAGE..1
(-7775 5450);
FORCEPROP 2 LAST $XR1 83 
J 0
(-8116 5450);
DISPLAY 0.638298 (-8116 5450);
PAINT MONO (-8116 5450);
FORCEPROP 2 LAST $XR0 81 
J 0
(-8026 5450);
DISPLAY 0.638298 (-8026 5450);
PAINT MONO (-8026 5450);
FORCEPROP 2 LAST CDS_LIB standard
J 0
(-7775 5450);
DISPLAY INVISIBLE (-7775 5450);
FORCEPROP 1 LAST OFFPAGE TRUE
J 0
(-7450 5325);
DISPLAY 0.872340 (-7450 5325);
PAINT GREEN (-7450 5325);
DISPLAY INVISIBLE (-7450 5325);
FORCEPROP 1 LAST COMMENT_BODY TRUE
J 0
(-7650 5350);
DISPLAY 0.872340 (-7650 5350);
PAINT GREEN (-7650 5350);
DISPLAY INVISIBLE (-7650 5350);
FORCEPROP 2 LAST PATH I339
J 0
(-8025 5500);
DISPLAY 1.021277 (-8025 5500);
DISPLAY INVISIBLE (-8025 5500);
FORCEADD OFFPAGE..3
R 2
(-7775 5250);
FORCEPROP 2 LAST $XR0 77 
J 0
(-8024 5250);
DISPLAY 0.638298 (-8024 5250);
PAINT MONO (-8024 5250);
FORCEPROP 2 LAST CDS_LIB standard
J 2
(-7775 5250);
DISPLAY INVISIBLE (-7775 5250);
FORCEPROP 1 LAST OFFPAGE TRUE
J 2
(-8100 5125);
DISPLAY 0.872340 (-8100 5125);
PAINT GREEN (-8100 5125);
DISPLAY INVISIBLE (-8100 5125);
FORCEPROP 1 LAST COMMENT_BODY TRUE
J 2
(-7725 5150);
DISPLAY 0.872340 (-7725 5150);
PAINT PEACH (-7725 5150);
DISPLAY INVISIBLE (-7725 5150);
FORCEPROP 2 LAST PATH I340
J 0
(-8050 5300);
DISPLAY 1.021277 (-8050 5300);
DISPLAY INVISIBLE (-8050 5300);
FORCEADD OFFPAGE..3
R 2
(-7775 5200);
FORCEPROP 2 LAST $XR0 77 
J 0
(-8024 5200);
DISPLAY 0.638298 (-8024 5200);
PAINT MONO (-8024 5200);
FORCEPROP 2 LAST CDS_LIB standard
J 2
(-7775 5200);
DISPLAY INVISIBLE (-7775 5200);
FORCEPROP 1 LAST OFFPAGE TRUE
J 2
(-8100 5075);
DISPLAY 0.872340 (-8100 5075);
PAINT GREEN (-8100 5075);
DISPLAY INVISIBLE (-8100 5075);
FORCEPROP 1 LAST COMMENT_BODY TRUE
J 2
(-7725 5100);
DISPLAY 0.872340 (-7725 5100);
PAINT PEACH (-7725 5100);
DISPLAY INVISIBLE (-7725 5100);
FORCEPROP 2 LAST PATH I341
J 0
(-8050 5250);
DISPLAY 1.021277 (-8050 5250);
DISPLAY INVISIBLE (-8050 5250);
FORCEADD OFFPAGE..3
R 2
(-7775 5100);
FORCEPROP 2 LAST $XR0 77 
J 0
(-8024 5100);
DISPLAY 0.638298 (-8024 5100);
PAINT MONO (-8024 5100);
FORCEPROP 2 LAST CDS_LIB standard
J 0
(-7775 5100);
DISPLAY INVISIBLE (-7775 5100);
FORCEPROP 1 LAST OFFPAGE TRUE
J 2
(-8100 4975);
DISPLAY 0.872340 (-8100 4975);
PAINT GREEN (-8100 4975);
DISPLAY INVISIBLE (-8100 4975);
FORCEPROP 1 LAST COMMENT_BODY TRUE
J 2
(-7725 5000);
DISPLAY 0.872340 (-7725 5000);
PAINT PEACH (-7725 5000);
DISPLAY INVISIBLE (-7725 5000);
FORCEPROP 2 LAST PATH I342
J 0
(-8050 5150);
DISPLAY 1.021277 (-8050 5150);
DISPLAY INVISIBLE (-8050 5150);
FORCEADD OFFPAGE..3
R 2
(-7775 5150);
FORCEPROP 2 LAST $XR0 77 
J 0
(-8024 5150);
DISPLAY 0.638298 (-8024 5150);
PAINT MONO (-8024 5150);
FORCEPROP 2 LAST CDS_LIB standard
J 0
(-7775 5150);
DISPLAY INVISIBLE (-7775 5150);
FORCEPROP 1 LAST OFFPAGE TRUE
J 2
(-8100 5025);
DISPLAY 0.872340 (-8100 5025);
PAINT GREEN (-8100 5025);
DISPLAY INVISIBLE (-8100 5025);
FORCEPROP 1 LAST COMMENT_BODY TRUE
J 2
(-7725 5050);
DISPLAY 0.872340 (-7725 5050);
PAINT PEACH (-7725 5050);
DISPLAY INVISIBLE (-7725 5050);
FORCEPROP 2 LAST PATH I343
J 0
(-8050 5200);
DISPLAY 1.021277 (-8050 5200);
DISPLAY INVISIBLE (-8050 5200);
FORCEADD OFFPAGE..3
R 2
(-7775 4950);
FORCEPROP 2 LAST $XR2 150 
J 0
(-8234 4950);
DISPLAY 0.638298 (-8234 4950);
PAINT MONO (-8234 4950);
FORCEPROP 2 LAST $XR1 81 
J 0
(-8114 4950);
DISPLAY 0.638298 (-8114 4950);
PAINT MONO (-8114 4950);
FORCEPROP 2 LAST $XR0 29 
J 0
(-8024 4950);
DISPLAY 0.638298 (-8024 4950);
PAINT MONO (-8024 4950);
FORCEPROP 2 LAST CDS_LIB standard
J 2
(-7775 4950);
DISPLAY INVISIBLE (-7775 4950);
FORCEPROP 1 LAST OFFPAGE TRUE
J 2
(-8100 4825);
DISPLAY 0.872340 (-8100 4825);
PAINT GREEN (-8100 4825);
DISPLAY INVISIBLE (-8100 4825);
FORCEPROP 1 LAST COMMENT_BODY TRUE
J 2
(-7725 4850);
DISPLAY 0.872340 (-7725 4850);
PAINT PEACH (-7725 4850);
DISPLAY INVISIBLE (-7725 4850);
FORCEPROP 2 LAST PATH I345
J 0
(-8050 5000);
DISPLAY 1.021277 (-8050 5000);
DISPLAY INVISIBLE (-8050 5000);
FORCEADD OFFPAGE..3
R 2
(-7775 4850);
FORCEPROP 2 LAST $XR2 150 
J 0
(-8234 4850);
DISPLAY 0.638298 (-8234 4850);
PAINT MONO (-8234 4850);
FORCEPROP 2 LAST $XR1 81 
J 0
(-8114 4850);
DISPLAY 0.638298 (-8114 4850);
PAINT MONO (-8114 4850);
FORCEPROP 2 LAST $XR0 29 
J 0
(-8024 4850);
DISPLAY 0.638298 (-8024 4850);
PAINT MONO (-8024 4850);
FORCEPROP 2 LAST CDS_LIB standard
J 0
(-7775 4850);
DISPLAY INVISIBLE (-7775 4850);
FORCEPROP 1 LAST OFFPAGE TRUE
J 2
(-8100 4725);
DISPLAY 0.872340 (-8100 4725);
PAINT GREEN (-8100 4725);
DISPLAY INVISIBLE (-8100 4725);
FORCEPROP 1 LAST COMMENT_BODY TRUE
J 2
(-7725 4750);
DISPLAY 0.872340 (-7725 4750);
PAINT PEACH (-7725 4750);
DISPLAY INVISIBLE (-7725 4750);
FORCEPROP 2 LAST PATH I346
J 0
(-8050 4900);
DISPLAY 1.021277 (-8050 4900);
DISPLAY INVISIBLE (-8050 4900);
FORCEADD OFFPAGE..3
R 2
(-7775 4900);
FORCEPROP 2 LAST $XR2 150 
J 0
(-8234 4900);
DISPLAY 0.638298 (-8234 4900);
PAINT MONO (-8234 4900);
FORCEPROP 2 LAST $XR1 81 
J 0
(-8114 4900);
DISPLAY 0.638298 (-8114 4900);
PAINT MONO (-8114 4900);
FORCEPROP 2 LAST $XR0 29 
J 0
(-8024 4900);
DISPLAY 0.638298 (-8024 4900);
PAINT MONO (-8024 4900);
FORCEPROP 2 LAST CDS_LIB standard
J 2
(-7775 4900);
DISPLAY INVISIBLE (-7775 4900);
FORCEPROP 1 LAST OFFPAGE TRUE
J 2
(-8100 4775);
DISPLAY 0.872340 (-8100 4775);
PAINT GREEN (-8100 4775);
DISPLAY INVISIBLE (-8100 4775);
FORCEPROP 1 LAST COMMENT_BODY TRUE
J 2
(-7725 4800);
DISPLAY 0.872340 (-7725 4800);
PAINT PEACH (-7725 4800);
DISPLAY INVISIBLE (-7725 4800);
FORCEPROP 2 LAST PATH I347
J 0
(-8050 4950);
DISPLAY 1.021277 (-8050 4950);
DISPLAY INVISIBLE (-8050 4950);
FORCEADD OFFPAGE..3
R 2
(-7775 4800);
FORCEPROP 2 LAST $XR2 150 
J 0
(-8234 4800);
DISPLAY 0.638298 (-8234 4800);
PAINT MONO (-8234 4800);
FORCEPROP 2 LAST $XR1 81 
J 0
(-8114 4800);
DISPLAY 0.638298 (-8114 4800);
PAINT MONO (-8114 4800);
FORCEPROP 2 LAST $XR0 29 
J 0
(-8024 4800);
DISPLAY 0.638298 (-8024 4800);
PAINT MONO (-8024 4800);
FORCEPROP 2 LAST CDS_LIB standard
J 0
(-7775 4800);
DISPLAY INVISIBLE (-7775 4800);
FORCEPROP 1 LAST OFFPAGE TRUE
J 2
(-8100 4675);
DISPLAY 0.872340 (-8100 4675);
PAINT GREEN (-8100 4675);
DISPLAY INVISIBLE (-8100 4675);
FORCEPROP 1 LAST COMMENT_BODY TRUE
J 2
(-7725 4700);
DISPLAY 0.872340 (-7725 4700);
PAINT PEACH (-7725 4700);
DISPLAY INVISIBLE (-7725 4700);
FORCEPROP 2 LAST PATH I348
J 0
(-8050 4850);
DISPLAY 1.021277 (-8050 4850);
DISPLAY INVISIBLE (-8050 4850);
FORCEADD OFFPAGE..2
R 2
(-7775 4450);
FORCEPROP 2 LAST $XR2 150 
J 0
(-8209 4450);
DISPLAY 0.638298 (-8209 4450);
PAINT MONO (-8209 4450);
FORCEPROP 2 LAST $XR1 81 
J 0
(-8089 4450);
DISPLAY 0.638298 (-8089 4450);
PAINT MONO (-8089 4450);
FORCEPROP 2 LAST $XR0 76 
J 0
(-7999 4450);
DISPLAY 0.638298 (-7999 4450);
PAINT MONO (-7999 4450);
FORCEPROP 2 LAST CDS_LIB standard
J 0
(-7775 4450);
DISPLAY INVISIBLE (-7775 4450);
FORCEPROP 1 LAST OFFPAGE TRUE
J 2
(-8100 4325);
DISPLAY 0.872340 (-8100 4325);
PAINT GREEN (-8100 4325);
DISPLAY INVISIBLE (-8100 4325);
FORCEPROP 1 LAST COMMENT_BODY TRUE
J 2
(-7730 4355);
DISPLAY 0.872340 (-7730 4355);
PAINT PEACH (-7730 4355);
DISPLAY INVISIBLE (-7730 4355);
FORCEPROP 2 LAST PATH I349
J 0
(-8025 4500);
DISPLAY 1.021277 (-8025 4500);
DISPLAY INVISIBLE (-8025 4500);
FORCEADD OFFPAGE..1
(-7775 4400);
FORCEPROP 2 LAST $XR0 76 
J 0
(-8026 4400);
DISPLAY 0.638298 (-8026 4400);
PAINT MONO (-8026 4400);
FORCEPROP 2 LAST CDS_LIB standard
J 0
(-7775 4400);
DISPLAY INVISIBLE (-7775 4400);
FORCEPROP 1 LAST OFFPAGE TRUE
J 0
(-7450 4275);
DISPLAY 0.872340 (-7450 4275);
PAINT GREEN (-7450 4275);
DISPLAY INVISIBLE (-7450 4275);
FORCEPROP 1 LAST COMMENT_BODY TRUE
J 0
(-7650 4300);
DISPLAY 0.872340 (-7650 4300);
PAINT GREEN (-7650 4300);
DISPLAY INVISIBLE (-7650 4300);
FORCEPROP 2 LAST PATH I350
J 0
(-8050 4450);
DISPLAY 1.021277 (-8050 4450);
DISPLAY INVISIBLE (-8050 4450);
FORCEADD OFFPAGE..2
R 2
(-7775 4350);
FORCEPROP 2 LAST $XR2 150 
J 0
(-8209 4350);
DISPLAY 0.638298 (-8209 4350);
PAINT MONO (-8209 4350);
FORCEPROP 2 LAST $XR1 81 
J 0
(-8089 4350);
DISPLAY 0.638298 (-8089 4350);
PAINT MONO (-8089 4350);
FORCEPROP 2 LAST $XR0 29 
J 0
(-7999 4350);
DISPLAY 0.638298 (-7999 4350);
PAINT MONO (-7999 4350);
FORCEPROP 2 LAST CDS_LIB standard
J 0
(-7775 4350);
DISPLAY INVISIBLE (-7775 4350);
FORCEPROP 1 LAST OFFPAGE TRUE
J 2
(-8100 4225);
DISPLAY 0.872340 (-8100 4225);
PAINT GREEN (-8100 4225);
DISPLAY INVISIBLE (-8100 4225);
FORCEPROP 1 LAST COMMENT_BODY TRUE
J 2
(-7730 4255);
DISPLAY 0.872340 (-7730 4255);
PAINT PEACH (-7730 4255);
DISPLAY INVISIBLE (-7730 4255);
FORCEPROP 2 LAST PATH I351
J 0
(-7975 4400);
DISPLAY 1.021277 (-7975 4400);
DISPLAY INVISIBLE (-7975 4400);
FORCEADD OFFPAGE..2
R 2
(-7775 4250);
FORCEPROP 2 LAST $XR0 77 
J 0
(-7999 4250);
DISPLAY 0.638298 (-7999 4250);
PAINT MONO (-7999 4250);
FORCEPROP 2 LAST CDS_LIB standard
J 0
(-7775 4250);
DISPLAY INVISIBLE (-7775 4250);
FORCEPROP 1 LAST OFFPAGE TRUE
J 2
(-8100 4125);
DISPLAY 0.872340 (-8100 4125);
PAINT GREEN (-8100 4125);
DISPLAY INVISIBLE (-8100 4125);
FORCEPROP 1 LAST COMMENT_BODY TRUE
J 2
(-7730 4155);
DISPLAY 0.872340 (-7730 4155);
PAINT PEACH (-7730 4155);
DISPLAY INVISIBLE (-7730 4155);
FORCEPROP 2 LAST PATH I352
J 0
(-8025 4300);
DISPLAY 1.021277 (-8025 4300);
DISPLAY INVISIBLE (-8025 4300);
FORCEADD OFFPAGE..3
(-2475 5900);
FORCEPROP 2 LAST $XR0 180 
J 0
(-2261 5900);
DISPLAY 0.638298 (-2261 5900);
PAINT MONO (-2261 5900);
FORCEPROP 2 LAST CDS_LIB standard
J 0
(-2475 5900);
DISPLAY INVISIBLE (-2475 5900);
FORCEPROP 1 LAST OFFPAGE TRUE
J 0
(-2150 5775);
DISPLAY 0.872340 (-2150 5775);
PAINT GREEN (-2150 5775);
DISPLAY INVISIBLE (-2150 5775);
FORCEPROP 1 LAST COMMENT_BODY TRUE
J 0
(-2525 5800);
DISPLAY 0.872340 (-2525 5800);
PAINT GREEN (-2525 5800);
DISPLAY INVISIBLE (-2525 5800);
FORCEPROP 2 LAST PATH I353
J 0
(-2250 5950);
DISPLAY 1.021277 (-2250 5950);
DISPLAY INVISIBLE (-2250 5950);
FORCEADD OFFPAGE..3
(-2475 5850);
FORCEPROP 2 LAST $XR0 180 
J 0
(-2261 5850);
DISPLAY 0.638298 (-2261 5850);
PAINT MONO (-2261 5850);
FORCEPROP 2 LAST CDS_LIB standard
J 0
(-2475 5850);
DISPLAY INVISIBLE (-2475 5850);
FORCEPROP 1 LAST OFFPAGE TRUE
J 0
(-2150 5725);
DISPLAY 0.872340 (-2150 5725);
PAINT GREEN (-2150 5725);
DISPLAY INVISIBLE (-2150 5725);
FORCEPROP 1 LAST COMMENT_BODY TRUE
J 0
(-2525 5750);
DISPLAY 0.872340 (-2525 5750);
PAINT GREEN (-2525 5750);
DISPLAY INVISIBLE (-2525 5750);
FORCEPROP 2 LAST PATH I354
J 0
(-2250 5900);
DISPLAY 1.021277 (-2250 5900);
DISPLAY INVISIBLE (-2250 5900);
FORCEADD OFFPAGE..3
(-2475 5750);
FORCEPROP 2 LAST $XR0 150 
J 0
(-2261 5750);
DISPLAY 0.638298 (-2261 5750);
PAINT MONO (-2261 5750);
FORCEPROP 2 LAST CDS_LIB standard
J 0
(-2475 5750);
DISPLAY INVISIBLE (-2475 5750);
FORCEPROP 1 LAST OFFPAGE TRUE
J 0
(-2150 5625);
DISPLAY 0.872340 (-2150 5625);
PAINT GREEN (-2150 5625);
DISPLAY INVISIBLE (-2150 5625);
FORCEPROP 1 LAST COMMENT_BODY TRUE
J 0
(-2525 5650);
DISPLAY 0.872340 (-2525 5650);
PAINT GREEN (-2525 5650);
DISPLAY INVISIBLE (-2525 5650);
FORCEPROP 2 LAST PATH I355
J 0
(-2250 5800);
DISPLAY 1.021277 (-2250 5800);
DISPLAY INVISIBLE (-2250 5800);
FORCEADD OFFPAGE..3
(-2475 5700);
FORCEPROP 2 LAST $XR0 150 
J 0
(-2261 5700);
DISPLAY 0.638298 (-2261 5700);
PAINT MONO (-2261 5700);
FORCEPROP 2 LAST CDS_LIB standard
J 0
(-2475 5700);
DISPLAY INVISIBLE (-2475 5700);
FORCEPROP 1 LAST OFFPAGE TRUE
J 0
(-2150 5575);
DISPLAY 0.872340 (-2150 5575);
PAINT GREEN (-2150 5575);
DISPLAY INVISIBLE (-2150 5575);
FORCEPROP 1 LAST COMMENT_BODY TRUE
J 0
(-2525 5600);
DISPLAY 0.872340 (-2525 5600);
PAINT GREEN (-2525 5600);
DISPLAY INVISIBLE (-2525 5600);
FORCEPROP 2 LAST PATH I356
J 0
(-2250 5750);
DISPLAY 1.021277 (-2250 5750);
DISPLAY INVISIBLE (-2250 5750);
FORCEADD OFFPAGE..3
(-2475 5600);
FORCEPROP 2 LAST $XR0 137 
J 0
(-2261 5600);
DISPLAY 0.638298 (-2261 5600);
PAINT MONO (-2261 5600);
FORCEPROP 2 LAST CDS_LIB standard
J 0
(-2475 5600);
DISPLAY INVISIBLE (-2475 5600);
FORCEPROP 1 LAST OFFPAGE TRUE
J 0
(-2150 5475);
DISPLAY 0.872340 (-2150 5475);
PAINT GREEN (-2150 5475);
DISPLAY INVISIBLE (-2150 5475);
FORCEPROP 1 LAST COMMENT_BODY TRUE
J 0
(-2525 5500);
DISPLAY 0.872340 (-2525 5500);
PAINT GREEN (-2525 5500);
DISPLAY INVISIBLE (-2525 5500);
FORCEPROP 2 LAST PATH I365
J 0
(-2250 5650);
DISPLAY 1.021277 (-2250 5650);
DISPLAY INVISIBLE (-2250 5650);
FORCEADD OFFPAGE..3
(-2475 5550);
FORCEPROP 2 LAST $XR0 137 
J 0
(-2261 5550);
DISPLAY 0.638298 (-2261 5550);
PAINT MONO (-2261 5550);
FORCEPROP 2 LAST CDS_LIB standard
J 0
(-2475 5550);
DISPLAY INVISIBLE (-2475 5550);
FORCEPROP 1 LAST OFFPAGE TRUE
J 0
(-2150 5425);
DISPLAY 0.872340 (-2150 5425);
PAINT GREEN (-2150 5425);
DISPLAY INVISIBLE (-2150 5425);
FORCEPROP 1 LAST COMMENT_BODY TRUE
J 0
(-2525 5450);
DISPLAY 0.872340 (-2525 5450);
PAINT GREEN (-2525 5450);
DISPLAY INVISIBLE (-2525 5450);
FORCEPROP 2 LAST PATH I366
J 0
(-2250 5600);
DISPLAY 1.021277 (-2250 5600);
DISPLAY INVISIBLE (-2250 5600);
FORCEADD OFFPAGE..1
R 2
(-1225 3950);
FORCEPROP 2 LAST $XR0 29 
J 0
(-1039 3950);
DISPLAY 0.638298 (-1039 3950);
PAINT MONO (-1039 3950);
FORCEPROP 2 LAST CDS_LIB standard
J 0
(-1225 3950);
DISPLAY INVISIBLE (-1225 3950);
FORCEPROP 1 LAST OFFPAGE TRUE
J 2
(-1550 3825);
DISPLAY 0.872340 (-1550 3825);
PAINT GREEN (-1550 3825);
DISPLAY INVISIBLE (-1550 3825);
FORCEPROP 1 LAST COMMENT_BODY TRUE
J 2
(-1350 3850);
DISPLAY 0.872340 (-1350 3850);
PAINT GREEN (-1350 3850);
DISPLAY INVISIBLE (-1350 3850);
FORCEPROP 2 LAST PATH I372
J 0
(-1050 4025);
DISPLAY 1.021277 (-1050 4025);
DISPLAY INVISIBLE (-1050 4025);
FORCEADD SN74LVC1G07DBVR..1
(-3375 2175);
FORCEPROP 1 LAST LOCATION U3
J 0
(-3500 2430);
DISPLAY 0.489362 (-3500 2430);
PAINT SKYBLUE (-3500 2430);
FORCEPROP 0 LAST $SEC 1
J 0
(-3500 2575);
DISPLAY 0.680851 (-3500 2575);
PAINT MONO (-3500 2575);
DISPLAY INVISIBLE (-3500 2575);
FORCEPROP 0 LAST CDS_SEC 1
J 0
(-3500 2575);
DISPLAY 1.021277 (-3500 2575);
DISPLAY INVISIBLE (-3500 2575);
FORCEPROP 0 LASTPIN (-3550 2175) $PN 2
J 2
(-3560 2185);
DISPLAY 0.489362 (-3560 2185);
PAINT MONO (-3560 2185);
FORCEPROP 0 LASTPIN (-3550 2075) $PN 3
J 2
(-3560 2085);
DISPLAY 0.489362 (-3560 2085);
PAINT MONO (-3560 2085);
FORCEPROP 0 LASTPIN (-3200 2075) $PN 1
J 0
(-3190 2085);
DISPLAY 0.489362 (-3190 2085);
PAINT MONO (-3190 2085);
FORCEPROP 0 LASTPIN (-3550 2275) $PN 5
J 2
(-3560 2285);
DISPLAY 0.489362 (-3560 2285);
PAINT MONO (-3560 2285);
FORCEPROP 0 LASTPIN (-3200 2175) $PN 4
J 0
(-3190 2185);
DISPLAY 0.489362 (-3190 2185);
PAINT MONO (-3190 2185);
FORCEPROP 1 LAST MATERIAL IC
J 0
(-3500 2335);
DISPLAY 0.489362 (-3500 2335);
PAINT SKYBLUE (-3500 2335);
FORCEPROP 2 LAST PACK_TYPE SMLF
J 0
(-3500 2475);
DISPLAY 0.489362 (-3500 2475);
PAINT SKYBLUE (-3500 2475);
FORCEPROP 2 LAST VALUE SN74LVC1G07DBVR
J 0
(-3500 2525);
DISPLAY 0.489362 (-3500 2525);
PAINT SKYBLUE (-3500 2525);
FORCEPROP 1 LAST NEEDS_NO_SIZE TRUE
J 0
(-3375 2175);
DISPLAY 0.468085 (-3375 2175);
PAINT GREEN (-3375 2175);
DISPLAY INVISIBLE (-3375 2175);
FORCEPROP 2 LAST CDS_LIB pure_quanta
J 0
(-3375 2175);
DISPLAY INVISIBLE (-3375 2175);
FORCEPROP 1 LAST PATH I373
J 0
(-3275 2330);
DISPLAY 0.723404 (-3275 2330);
PAINT GREEN (-3275 2330);
DISPLAY INVISIBLE (-3275 2330);
FORCEPROP 1 LAST PART_NUMBER AL1G0007024
J 0
(-3500 2385);
DISPLAY 0.489362 (-3500 2385);
PAINT SKYBLUE (-3500 2385);
DISPLAY INVISIBLE (-3500 2385);
FORCEADD OFFPAGE..1
(-4600 2175);
FORCEPROP 2 LAST $XR1 83 
J 0
(-4911 2175);
DISPLAY 0.638298 (-4911 2175);
PAINT MONO (-4911 2175);
FORCEPROP 2 LAST $XR0 81 
J 0
(-4821 2175);
DISPLAY 0.638298 (-4821 2175);
PAINT MONO (-4821 2175);
FORCEPROP 2 LAST CDS_LIB standard
J 0
(-4600 2175);
DISPLAY INVISIBLE (-4600 2175);
FORCEPROP 1 LAST OFFPAGE TRUE
J 0
(-4275 2050);
DISPLAY 0.872340 (-4275 2050);
PAINT GREEN (-4275 2050);
DISPLAY INVISIBLE (-4275 2050);
FORCEPROP 1 LAST COMMENT_BODY TRUE
J 0
(-4475 2075);
DISPLAY 0.872340 (-4475 2075);
PAINT GREEN (-4475 2075);
DISPLAY INVISIBLE (-4475 2075);
FORCEPROP 2 LAST PATH I376
J 0
(-4550 2250);
DISPLAY 1.021277 (-4550 2250);
DISPLAY INVISIBLE (-4550 2250);
FORCEADD Q_RES..1
(-2525 2175);
FORCEPROP 1 LAST LOCATION R589
J 0
(-2575 2225);
DISPLAY 0.489362 (-2575 2225);
PAINT SKYBLUE (-2575 2225);
FORCEPROP 0 LAST $SEC 1
J 0
(-2575 2275);
DISPLAY 0.680851 (-2575 2275);
PAINT MONO (-2575 2275);
DISPLAY INVISIBLE (-2575 2275);
FORCEPROP 0 LAST CDS_SEC 1
J 0
(-2575 2275);
DISPLAY 1.021277 (-2575 2275);
DISPLAY INVISIBLE (-2575 2275);
FORCEPROP 1 LASTPIN (-2625 2175) $PN 1
J 0
(-2613 2187);
DISPLAY 0.489362 (-2613 2187);
PAINT MONO (-2613 2187);
FORCEPROP 1 LASTPIN (-2425 2175) $PN 2
J 0
(-2463 2187);
DISPLAY 0.489362 (-2463 2187);
PAINT MONO (-2463 2187);
FORCEPROP 1 LAST VALUE 0
J 2
(-2625 2175);
DISPLAY 0.489362 (-2625 2175);
PAINT SKYBLUE (-2625 2175);
FORCEPROP 1 LAST PACK_TYPE 0402LF
J 0
(-2475 2100);
DISPLAY 0.489362 (-2475 2100);
PAINT SKYBLUE (-2475 2100);
DISPLAY INVISIBLE (-2475 2100);
FORCEPROP 1 LAST TOLERANCE 5%
J 0
(-2550 2100);
DISPLAY 0.489362 (-2550 2100);
PAINT SKYBLUE (-2550 2100);
DISPLAY INVISIBLE (-2550 2100);
FORCEPROP 1 LAST MATERIAL CHIP
J 0
(-2100 2100);
DISPLAY 0.489362 (-2100 2100);
PAINT SKYBLUE (-2100 2100);
DISPLAY INVISIBLE (-2100 2100);
FORCEPROP 1 LAST WATTAGE 1/16W
J 2
(-2125 2100);
DISPLAY 0.489362 (-2125 2100);
PAINT SKYBLUE (-2125 2100);
DISPLAY INVISIBLE (-2125 2100);
FORCEPROP 2 LAST CDS_LIB pure_quanta
J 0
(-2525 2175);
DISPLAY INVISIBLE (-2525 2175);
FORCEPROP 1 LAST PATH I377
J 0
(-2575 2325);
DISPLAY 0.978723 (-2575 2325);
PAINT WHITE (-2575 2325);
DISPLAY INVISIBLE (-2575 2325);
FORCEPROP 1 LAST PART_NUMBER CS00002JB13
J 0
(-2500 2225);
DISPLAY 0.489362 (-2500 2225);
PAINT SKYBLUE (-2500 2225);
DISPLAY INVISIBLE (-2500 2225);
FORCEADD Q_CAP..1
R 2
(-3725 2475);
FORCEPROP 1 LAST LOCATION C30
J 2
(-3775 2600);
DISPLAY 0.489362 (-3775 2600);
PAINT SKYBLUE (-3775 2600);
FORCEPROP 0 LAST $SEC 1
J 0
(-3775 2650);
DISPLAY 0.680851 (-3775 2650);
PAINT MONO (-3775 2650);
DISPLAY INVISIBLE (-3775 2650);
FORCEPROP 0 LAST CDS_SEC 1
J 0
(-3775 2650);
DISPLAY 1.021277 (-3775 2650);
DISPLAY INVISIBLE (-3775 2650);
FORCEPROP 1 LASTPIN (-3725 2575) $PN 1
J 2
(-3735 2555);
DISPLAY 0.489362 (-3735 2555);
PAINT MONO (-3735 2555);
FORCEPROP 1 LASTPIN (-3725 2375) $PN 2
J 2
(-3735 2355);
DISPLAY 0.489362 (-3735 2355);
PAINT MONO (-3735 2355);
FORCEPROP 1 LAST MATERIAL X7R
J 2
(-3775 2425);
DISPLAY 0.489362 (-3775 2425);
PAINT SKYBLUE (-3775 2425);
FORCEPROP 1 LAST PACK_TYPE 0402
J 2
(-3775 2375);
DISPLAY 0.489362 (-3775 2375);
PAINT SKYBLUE (-3775 2375);
FORCEPROP 1 LAST TOLERANCE 10%
J 2
(-3775 2475);
DISPLAY 0.489362 (-3775 2475);
PAINT SKYBLUE (-3775 2475);
FORCEPROP 1 LAST VALUE 0.1UF
J 2
(-3775 2575);
DISPLAY 0.489362 (-3775 2575);
PAINT SKYBLUE (-3775 2575);
FORCEPROP 1 LAST VOLTAGE 25V
J 2
(-3775 2525);
DISPLAY 0.489362 (-3775 2525);
PAINT SKYBLUE (-3775 2525);
FORCEPROP 2 LAST CDS_LIB pure_quanta
J 0
(-3725 2475);
DISPLAY INVISIBLE (-3725 2475);
FORCEPROP 1 LAST PATH I379
J 2
(-3775 2625);
DISPLAY 0.978723 (-3775 2625);
PAINT WHITE (-3775 2625);
DISPLAY INVISIBLE (-3775 2625);
FORCEPROP 1 LAST PART_NUMBER CH4104K1B00
J 2
(-3775 2325);
DISPLAY 0.489362 (-3775 2325);
PAINT SKYBLUE (-3775 2325);
DISPLAY INVISIBLE (-3775 2325);
FORCEADD UNIVERSAL_GND..1
R 2
(-3725 2275);
FORCEPROP 3 LASTPIN (-3725 2325) SIG_NAME GND\g
J 0
(-3715 2335);
DISPLAY 0.659574 (-3715 2335);
PAINT MONO (-3715 2335);
DISPLAY INVISIBLE (-3715 2335);
FORCEPROP 2 LAST CDS_LIB pure_quanta_power
J 0
(-3725 2275);
DISPLAY INVISIBLE (-3725 2275);
FORCEPROP 1 LAST HDL_POWER GND
J 1
(-3750 2200);
DISPLAY 0.872340 (-3750 2200);
PAINT GREEN (-3750 2200);
DISPLAY INVISIBLE (-3750 2200);
FORCEPROP 1 LAST PATH I380
J 2
(-3800 2275);
DISPLAY 0.872340 (-3800 2275);
PAINT AQUA (-3800 2275);
DISPLAY INVISIBLE (-3800 2275);
FORCEADD UNIVERSAL_POWER..1
(-2350 2850);
FORCEPROP 3 LASTPIN (-2350 2800) SIG_NAME PVDD18_S5_P0\g
J 0
(-2340 2810);
DISPLAY 0.659574 (-2340 2810);
PAINT MONO (-2340 2810);
DISPLAY INVISIBLE (-2340 2810);
FORCEPROP 1 LAST HDL_POWER PVDD18_S5_P0
J 1
(-2350 2900);
DISPLAY 0.489362 (-2350 2900);
PAINT GREEN (-2350 2900);
FORCEPROP 2 LAST CDS_LIB pure_quanta_power
J 0
(-2350 2850);
DISPLAY INVISIBLE (-2350 2850);
FORCEPROP 1 LAST PATH I382
J 0
(-2300 2875);
DISPLAY 0.872340 (-2300 2875);
PAINT AQUA (-2300 2875);
DISPLAY INVISIBLE (-2300 2875);
FORCEADD Q_RES..2
(-2350 2575);
FORCEPROP 1 LAST LOCATION R454
J 0
(-2305 2700);
DISPLAY 0.489362 (-2305 2700);
PAINT SKYBLUE (-2305 2700);
FORCEPROP 0 LAST $SEC 1
J 0
(-2300 2750);
DISPLAY 0.680851 (-2300 2750);
PAINT MONO (-2300 2750);
DISPLAY INVISIBLE (-2300 2750);
FORCEPROP 0 LAST CDS_SEC 1
J 0
(-2300 2750);
DISPLAY 1.021277 (-2300 2750);
DISPLAY INVISIBLE (-2300 2750);
FORCEPROP 1 LASTPIN (-2350 2675) $PN 1
J 0
(-2345 2637);
DISPLAY 0.489362 (-2345 2637);
PAINT MONO (-2345 2637);
FORCEPROP 1 LASTPIN (-2350 2475) $PN 2
J 0
(-2345 2485);
DISPLAY 0.489362 (-2345 2485);
PAINT MONO (-2345 2485);
FORCEPROP 1 LAST PACK_TYPE 0402LF
J 0
(-2325 2450);
DISPLAY 0.489362 (-2325 2450);
PAINT SKYBLUE (-2325 2450);
FORCEPROP 1 LAST TOLERANCE 5%
J 0
(-2325 2600);
DISPLAY 0.489362 (-2325 2600);
PAINT SKYBLUE (-2325 2600);
FORCEPROP 1 LAST MATERIAL CHIP
J 0
(-2325 2500);
DISPLAY 0.489362 (-2325 2500);
PAINT SKYBLUE (-2325 2500);
FORCEPROP 1 LAST WATTAGE 1/16W
J 0
(-2325 2550);
DISPLAY 0.489362 (-2325 2550);
PAINT SKYBLUE (-2325 2550);
FORCEPROP 1 LAST VALUE 10K
J 0
(-2325 2650);
DISPLAY 0.489362 (-2325 2650);
PAINT SKYBLUE (-2325 2650);
FORCEPROP 2 LAST BOM_COST I/O CONNECTOR
J 0
(-2325 2700);
DISPLAY 0.680851 (-2325 2700);
DISPLAY INVISIBLE (-2325 2700);
FORCEPROP 2 LAST CDS_LIB pure_quanta
J 0
(-2350 2575);
DISPLAY INVISIBLE (-2350 2575);
FORCEPROP 1 LAST PATH I383
J 0
(-2300 2750);
DISPLAY 0.978723 (-2300 2750);
PAINT WHITE (-2300 2750);
DISPLAY INVISIBLE (-2300 2750);
FORCEPROP 1 LAST PART_NUMBER CS31002JB08
J 0
(-2335 2525);
DISPLAY 0.638298 (-2335 2525);
PAINT SKYBLUE (-2335 2525);
DISPLAY INVISIBLE (-2335 2525);
FORCEADD OFFPAGE..2
(-1625 2175);
FORCEPROP 2 LAST $XR0 29 
J 0
(-1436 2175);
DISPLAY 0.638298 (-1436 2175);
PAINT MONO (-1436 2175);
FORCEPROP 2 LAST CDS_LIB standard
J 0
(-1625 2175);
DISPLAY INVISIBLE (-1625 2175);
FORCEPROP 1 LAST OFFPAGE TRUE
J 0
(-1300 2050);
DISPLAY 0.872340 (-1300 2050);
PAINT GREEN (-1300 2050);
DISPLAY INVISIBLE (-1300 2050);
FORCEPROP 1 LAST COMMENT_BODY TRUE
J 0
(-1670 2080);
DISPLAY 0.872340 (-1670 2080);
PAINT GREEN (-1670 2080);
DISPLAY INVISIBLE (-1670 2080);
FORCEPROP 2 LAST PATH I384
J 0
(-1450 2250);
DISPLAY 1.021277 (-1450 2250);
DISPLAY INVISIBLE (-1450 2250);
FORCEADD UNIVERSAL_GND..1
(-3625 1950);
FORCEPROP 3 LASTPIN (-3625 2000) SIG_NAME GND\g
J 0
(-3615 2010);
DISPLAY 0.659574 (-3615 2010);
PAINT MONO (-3615 2010);
DISPLAY INVISIBLE (-3615 2010);
FORCEPROP 1 LAST HDL_POWER GND
J 1
(-3600 1875);
DISPLAY 0.489362 (-3600 1875);
PAINT GREEN (-3600 1875);
FORCEPROP 2 LAST CDS_LIB pure_quanta_power
J 0
(-3625 1950);
DISPLAY INVISIBLE (-3625 1950);
FORCEPROP 1 LAST PATH I385
J 0
(-3550 1950);
DISPLAY 0.872340 (-3550 1950);
PAINT AQUA (-3550 1950);
DISPLAY INVISIBLE (-3550 1950);
FORCEADD VCC_CORE..1
(-3650 2750);
FORCEPROP 3 LASTPIN (-3650 2700) SIG_NAME P1V8_AUX\g
J 0
(-3640 2710);
DISPLAY 0.659574 (-3640 2710);
PAINT MONO (-3640 2710);
DISPLAY INVISIBLE (-3640 2710);
FORCEPROP 1 LAST HDL_POWER P1V8_AUX
J 1
(-3650 2800);
DISPLAY 0.489362 (-3650 2800);
PAINT GREEN (-3650 2800);
FORCEPROP 2 LAST CDS_LIB pure_quanta_power
J 0
(-3650 2750);
DISPLAY INVISIBLE (-3650 2750);
FORCEPROP 1 LAST PATH I386
J 0
(-3600 2775);
DISPLAY 0.872340 (-3600 2775);
PAINT AQUA (-3600 2775);
DISPLAY INVISIBLE (-3600 2775);
FORCEADD OFFPAGE..2
R 2
(-7775 5550);
FORCEPROP 2 LAST $XR2 150 
J 0
(-8209 5550);
DISPLAY 0.638298 (-8209 5550);
PAINT MONO (-8209 5550);
FORCEPROP 2 LAST $XR1 81 
J 0
(-8089 5550);
DISPLAY 0.638298 (-8089 5550);
PAINT MONO (-8089 5550);
FORCEPROP 2 LAST $XR0 29 
J 0
(-7999 5550);
DISPLAY 0.638298 (-7999 5550);
PAINT MONO (-7999 5550);
FORCEPROP 2 LAST CDS_LIB standard
J 2
(-7775 5550);
DISPLAY INVISIBLE (-7775 5550);
FORCEPROP 1 LAST OFFPAGE TRUE
J 2
(-8100 5425);
DISPLAY 0.872340 (-8100 5425);
PAINT GREEN (-8100 5425);
DISPLAY INVISIBLE (-8100 5425);
FORCEPROP 1 LAST COMMENT_BODY TRUE
J 2
(-7730 5455);
DISPLAY 0.872340 (-7730 5455);
PAINT PEACH (-7730 5455);
DISPLAY INVISIBLE (-7730 5455);
FORCEPROP 2 LAST PATH I394
J 0
(-7975 5600);
DISPLAY 0.680851 (-7975 5600);
DISPLAY INVISIBLE (-7975 5600);
FORCEADD UNIVERSAL_POWER..1
(-8125 2625);
FORCEPROP 3 LASTPIN (-8125 2575) SIG_NAME PVDD18_S5_P0\g
J 0
(-8115 2585);
DISPLAY 0.659574 (-8115 2585);
PAINT MONO (-8115 2585);
DISPLAY INVISIBLE (-8115 2585);
FORCEPROP 1 LAST HDL_POWER PVDD18_S5_P0
J 1
(-8125 2675);
DISPLAY 0.489362 (-8125 2675);
PAINT GREEN (-8125 2675);
FORCEPROP 2 LAST CDS_LIB pure_quanta_power
J 0
(-8125 2625);
DISPLAY INVISIBLE (-8125 2625);
FORCEPROP 1 LAST PATH I395
J 0
(-8075 2650);
DISPLAY 0.872340 (-8075 2650);
PAINT AQUA (-8075 2650);
DISPLAY INVISIBLE (-8075 2650);
FORCEADD Q_RES..1
(-7750 2375);
FORCEPROP 1 LAST LOCATION R1503
J 0
(-7625 2375);
DISPLAY 0.489362 (-7625 2375);
PAINT SKYBLUE (-7625 2375);
FORCEPROP 0 LAST $SEC 1
J 0
(-7625 2400);
DISPLAY 0.680851 (-7625 2400);
PAINT MONO (-7625 2400);
DISPLAY INVISIBLE (-7625 2400);
FORCEPROP 0 LAST CDS_SEC 1
J 0
(-7625 2400);
DISPLAY 0.680851 (-7625 2400);
DISPLAY INVISIBLE (-7625 2400);
FORCEPROP 1 LASTPIN (-7850 2375) $PN 1
J 0
(-7838 2387);
DISPLAY 0.489362 (-7838 2387);
PAINT MONO (-7838 2387);
FORCEPROP 1 LASTPIN (-7650 2375) $PN 2
J 0
(-7688 2387);
DISPLAY 0.489362 (-7688 2387);
PAINT MONO (-7688 2387);
FORCEPROP 1 LAST MATERIAL CHIP
J 0
(-7500 2375);
DISPLAY 0.489362 (-7500 2375);
PAINT SKYBLUE (-7500 2375);
FORCEPROP 1 LAST VALUE 30K
J 2
(-7850 2375);
DISPLAY 0.489362 (-7850 2375);
PAINT SKYBLUE (-7850 2375);
FORCEPROP 1 LAST PACK_TYPE 0402LF
J 0
(-7700 2300);
DISPLAY 0.489362 (-7700 2300);
PAINT SKYBLUE (-7700 2300);
DISPLAY INVISIBLE (-7700 2300);
FORCEPROP 1 LAST TOLERANCE 1%
J 0
(-7775 2300);
DISPLAY 0.489362 (-7775 2300);
PAINT SKYBLUE (-7775 2300);
DISPLAY INVISIBLE (-7775 2300);
FORCEPROP 1 LAST WATTAGE 1/16W
J 2
(-7350 2300);
DISPLAY 0.489362 (-7350 2300);
PAINT SKYBLUE (-7350 2300);
DISPLAY INVISIBLE (-7350 2300);
FORCEPROP 2 LAST CDS_LIB pure_quanta
J 0
(-7750 2375);
DISPLAY INVISIBLE (-7750 2375);
FORCEPROP 1 LAST PATH I396
J 0
(-7800 2525);
DISPLAY 0.978723 (-7800 2525);
PAINT WHITE (-7800 2525);
DISPLAY INVISIBLE (-7800 2525);
FORCEPROP 1 LAST PART_NUMBER CS33002FB02
J 0
(-7725 2425);
DISPLAY 0.489362 (-7725 2425);
PAINT SKYBLUE (-7725 2425);
DISPLAY INVISIBLE (-7725 2425);
FORCEADD Q_RES..1
(-7750 2325);
FORCEPROP 1 LAST LOCATION R1504
J 0
(-7625 2325);
DISPLAY 0.489362 (-7625 2325);
PAINT SKYBLUE (-7625 2325);
FORCEPROP 0 LAST $SEC 1
J 0
(-7625 2375);
DISPLAY 0.680851 (-7625 2375);
PAINT MONO (-7625 2375);
DISPLAY INVISIBLE (-7625 2375);
FORCEPROP 0 LAST CDS_SEC 1
J 0
(-7625 2375);
DISPLAY 0.680851 (-7625 2375);
DISPLAY INVISIBLE (-7625 2375);
FORCEPROP 1 LASTPIN (-7850 2325) $PN 1
J 0
(-7838 2337);
DISPLAY 0.489362 (-7838 2337);
PAINT MONO (-7838 2337);
FORCEPROP 1 LASTPIN (-7650 2325) $PN 2
J 0
(-7688 2337);
DISPLAY 0.489362 (-7688 2337);
PAINT MONO (-7688 2337);
FORCEPROP 1 LAST VALUE 30K
J 2
(-7850 2325);
DISPLAY 0.489362 (-7850 2325);
PAINT SKYBLUE (-7850 2325);
FORCEPROP 1 LAST MATERIAL CHIP
J 0
(-7500 2325);
DISPLAY 0.489362 (-7500 2325);
PAINT SKYBLUE (-7500 2325);
FORCEPROP 2 LAST CDS_LIB pure_quanta
J 0
(-7750 2325);
DISPLAY INVISIBLE (-7750 2325);
FORCEPROP 1 LAST WATTAGE 1/16W
J 2
(-7350 2250);
DISPLAY 0.489362 (-7350 2250);
PAINT SKYBLUE (-7350 2250);
DISPLAY INVISIBLE (-7350 2250);
FORCEPROP 1 LAST TOLERANCE 1%
J 0
(-7775 2250);
DISPLAY 0.489362 (-7775 2250);
PAINT SKYBLUE (-7775 2250);
DISPLAY INVISIBLE (-7775 2250);
FORCEPROP 1 LAST PACK_TYPE 0402LF
J 0
(-7700 2250);
DISPLAY 0.489362 (-7700 2250);
PAINT SKYBLUE (-7700 2250);
DISPLAY INVISIBLE (-7700 2250);
FORCEPROP 1 LAST PATH I397
J 0
(-7800 2475);
DISPLAY 0.978723 (-7800 2475);
PAINT WHITE (-7800 2475);
DISPLAY INVISIBLE (-7800 2475);
FORCEPROP 1 LAST PART_NUMBER CS33002FB02
J 0
(-7725 2375);
DISPLAY 0.489362 (-7725 2375);
PAINT SKYBLUE (-7725 2375);
DISPLAY INVISIBLE (-7725 2375);
FORCEADD Q_RES..1
(-7750 2275);
FORCEPROP 1 LAST LOCATION R1505
J 0
(-7625 2275);
DISPLAY 0.489362 (-7625 2275);
PAINT SKYBLUE (-7625 2275);
FORCEPROP 0 LAST $SEC 1
J 0
(-7625 2325);
DISPLAY 0.680851 (-7625 2325);
PAINT MONO (-7625 2325);
DISPLAY INVISIBLE (-7625 2325);
FORCEPROP 0 LAST CDS_SEC 1
J 0
(-7625 2325);
DISPLAY 0.680851 (-7625 2325);
DISPLAY INVISIBLE (-7625 2325);
FORCEPROP 1 LASTPIN (-7850 2275) $PN 1
J 0
(-7838 2287);
DISPLAY 0.489362 (-7838 2287);
PAINT MONO (-7838 2287);
FORCEPROP 1 LASTPIN (-7650 2275) $PN 2
J 0
(-7688 2287);
DISPLAY 0.489362 (-7688 2287);
PAINT MONO (-7688 2287);
FORCEPROP 1 LAST MATERIAL CHIP
J 0
(-7500 2275);
DISPLAY 0.489362 (-7500 2275);
PAINT SKYBLUE (-7500 2275);
FORCEPROP 1 LAST VALUE 30K
J 2
(-7850 2275);
DISPLAY 0.489362 (-7850 2275);
PAINT SKYBLUE (-7850 2275);
FORCEPROP 2 LAST CDS_LIB pure_quanta
J 0
(-7750 2275);
DISPLAY INVISIBLE (-7750 2275);
FORCEPROP 1 LAST WATTAGE 1/16W
J 2
(-7350 2200);
DISPLAY 0.489362 (-7350 2200);
PAINT SKYBLUE (-7350 2200);
DISPLAY INVISIBLE (-7350 2200);
FORCEPROP 1 LAST TOLERANCE 1%
J 0
(-7775 2200);
DISPLAY 0.489362 (-7775 2200);
PAINT SKYBLUE (-7775 2200);
DISPLAY INVISIBLE (-7775 2200);
FORCEPROP 1 LAST PACK_TYPE 0402LF
J 0
(-7700 2200);
DISPLAY 0.489362 (-7700 2200);
PAINT SKYBLUE (-7700 2200);
DISPLAY INVISIBLE (-7700 2200);
FORCEPROP 1 LAST PATH I398
J 0
(-7800 2425);
DISPLAY 0.978723 (-7800 2425);
PAINT WHITE (-7800 2425);
DISPLAY INVISIBLE (-7800 2425);
FORCEPROP 1 LAST PART_NUMBER CS33002FB02
J 0
(-7725 2325);
DISPLAY 0.489362 (-7725 2325);
PAINT SKYBLUE (-7725 2325);
DISPLAY INVISIBLE (-7725 2325);
FORCEADD Q_RES..1
(-7750 2225);
FORCEPROP 1 LAST LOCATION R1506
J 0
(-7625 2225);
DISPLAY 0.489362 (-7625 2225);
PAINT SKYBLUE (-7625 2225);
FORCEPROP 0 LAST $SEC 1
J 0
(-7625 2275);
DISPLAY 0.680851 (-7625 2275);
PAINT MONO (-7625 2275);
DISPLAY INVISIBLE (-7625 2275);
FORCEPROP 0 LAST CDS_SEC 1
J 0
(-7625 2275);
DISPLAY 0.680851 (-7625 2275);
DISPLAY INVISIBLE (-7625 2275);
FORCEPROP 1 LASTPIN (-7850 2225) $PN 1
J 0
(-7838 2237);
DISPLAY 0.489362 (-7838 2237);
PAINT MONO (-7838 2237);
FORCEPROP 1 LASTPIN (-7650 2225) $PN 2
J 0
(-7688 2237);
DISPLAY 0.489362 (-7688 2237);
PAINT MONO (-7688 2237);
FORCEPROP 1 LAST VALUE 30K
J 2
(-7850 2225);
DISPLAY 0.489362 (-7850 2225);
PAINT SKYBLUE (-7850 2225);
FORCEPROP 1 LAST MATERIAL CHIP
J 0
(-7500 2225);
DISPLAY 0.489362 (-7500 2225);
PAINT SKYBLUE (-7500 2225);
FORCEPROP 2 LAST CDS_LIB pure_quanta
J 0
(-7750 2225);
DISPLAY INVISIBLE (-7750 2225);
FORCEPROP 1 LAST WATTAGE 1/16W
J 2
(-7350 2150);
DISPLAY 0.489362 (-7350 2150);
PAINT SKYBLUE (-7350 2150);
DISPLAY INVISIBLE (-7350 2150);
FORCEPROP 1 LAST TOLERANCE 1%
J 0
(-7775 2150);
DISPLAY 0.489362 (-7775 2150);
PAINT SKYBLUE (-7775 2150);
DISPLAY INVISIBLE (-7775 2150);
FORCEPROP 1 LAST PACK_TYPE 0402LF
J 0
(-7700 2150);
DISPLAY 0.489362 (-7700 2150);
PAINT SKYBLUE (-7700 2150);
DISPLAY INVISIBLE (-7700 2150);
FORCEPROP 1 LAST PATH I399
J 0
(-7800 2375);
DISPLAY 0.978723 (-7800 2375);
PAINT WHITE (-7800 2375);
DISPLAY INVISIBLE (-7800 2375);
FORCEPROP 1 LAST PART_NUMBER CS33002FB02
J 0
(-7725 2275);
DISPLAY 0.489362 (-7725 2275);
PAINT SKYBLUE (-7725 2275);
DISPLAY INVISIBLE (-7725 2275);
FORCEADD OFFPAGE..2
(-6850 2375);
FORCEPROP 2 LAST $XR2 150 
J 0
(-6481 2375);
DISPLAY 0.638298 (-6481 2375);
PAINT MONO (-6481 2375);
FORCEPROP 2 LAST $XR1 81 
J 0
(-6571 2375);
DISPLAY 0.638298 (-6571 2375);
PAINT MONO (-6571 2375);
FORCEPROP 2 LAST $XR0 29 
J 0
(-6661 2375);
DISPLAY 0.638298 (-6661 2375);
PAINT MONO (-6661 2375);
FORCEPROP 2 LAST CDS_LIB standard
J 0
(-6850 2375);
DISPLAY INVISIBLE (-6850 2375);
FORCEPROP 1 LAST OFFPAGE TRUE
J 0
(-6525 2250);
DISPLAY 0.872340 (-6525 2250);
PAINT GREEN (-6525 2250);
DISPLAY INVISIBLE (-6525 2250);
FORCEPROP 1 LAST COMMENT_BODY TRUE
J 0
(-6895 2280);
DISPLAY 0.872340 (-6895 2280);
PAINT PEACH (-6895 2280);
DISPLAY INVISIBLE (-6895 2280);
FORCEPROP 2 LAST PATH I400
J 0
(-6675 2450);
DISPLAY 0.680851 (-6675 2450);
DISPLAY INVISIBLE (-6675 2450);
FORCEADD OFFPAGE..2
(-6850 2275);
FORCEPROP 2 LAST $XR2 150 
J 0
(-6481 2275);
DISPLAY 0.638298 (-6481 2275);
PAINT MONO (-6481 2275);
FORCEPROP 2 LAST $XR1 81 
J 0
(-6571 2275);
DISPLAY 0.638298 (-6571 2275);
PAINT MONO (-6571 2275);
FORCEPROP 2 LAST $XR0 29 
J 0
(-6661 2275);
DISPLAY 0.638298 (-6661 2275);
PAINT MONO (-6661 2275);
FORCEPROP 2 LAST CDS_LIB standard
J 0
(-6850 2275);
DISPLAY INVISIBLE (-6850 2275);
FORCEPROP 1 LAST OFFPAGE TRUE
J 0
(-6525 2150);
DISPLAY 0.872340 (-6525 2150);
PAINT GREEN (-6525 2150);
DISPLAY INVISIBLE (-6525 2150);
FORCEPROP 1 LAST COMMENT_BODY TRUE
J 0
(-6895 2180);
DISPLAY 0.872340 (-6895 2180);
PAINT PEACH (-6895 2180);
DISPLAY INVISIBLE (-6895 2180);
FORCEPROP 2 LAST PATH I401
J 0
(-6675 2350);
DISPLAY 0.680851 (-6675 2350);
DISPLAY INVISIBLE (-6675 2350);
FORCEADD OFFPAGE..2
(-6850 2325);
FORCEPROP 2 LAST $XR2 150 
J 0
(-6481 2325);
DISPLAY 0.638298 (-6481 2325);
PAINT MONO (-6481 2325);
FORCEPROP 2 LAST $XR1 81 
J 0
(-6571 2325);
DISPLAY 0.638298 (-6571 2325);
PAINT MONO (-6571 2325);
FORCEPROP 2 LAST $XR0 29 
J 0
(-6661 2325);
DISPLAY 0.638298 (-6661 2325);
PAINT MONO (-6661 2325);
FORCEPROP 2 LAST CDS_LIB standard
J 0
(-6850 2325);
DISPLAY INVISIBLE (-6850 2325);
FORCEPROP 1 LAST OFFPAGE TRUE
J 0
(-6525 2200);
DISPLAY 0.872340 (-6525 2200);
PAINT GREEN (-6525 2200);
DISPLAY INVISIBLE (-6525 2200);
FORCEPROP 1 LAST COMMENT_BODY TRUE
J 0
(-6895 2230);
DISPLAY 0.872340 (-6895 2230);
PAINT PEACH (-6895 2230);
DISPLAY INVISIBLE (-6895 2230);
FORCEPROP 2 LAST PATH I402
J 0
(-6675 2400);
DISPLAY 0.680851 (-6675 2400);
DISPLAY INVISIBLE (-6675 2400);
FORCEADD OFFPAGE..2
(-6850 2225);
FORCEPROP 2 LAST $XR2 150 
J 0
(-6481 2225);
DISPLAY 0.638298 (-6481 2225);
PAINT MONO (-6481 2225);
FORCEPROP 2 LAST $XR1 81 
J 0
(-6571 2225);
DISPLAY 0.638298 (-6571 2225);
PAINT MONO (-6571 2225);
FORCEPROP 2 LAST $XR0 29 
J 0
(-6661 2225);
DISPLAY 0.638298 (-6661 2225);
PAINT MONO (-6661 2225);
FORCEPROP 2 LAST CDS_LIB standard
J 0
(-6850 2225);
DISPLAY INVISIBLE (-6850 2225);
FORCEPROP 1 LAST OFFPAGE TRUE
J 0
(-6525 2100);
DISPLAY 0.872340 (-6525 2100);
PAINT GREEN (-6525 2100);
DISPLAY INVISIBLE (-6525 2100);
FORCEPROP 1 LAST COMMENT_BODY TRUE
J 0
(-6895 2130);
DISPLAY 0.872340 (-6895 2130);
PAINT PEACH (-6895 2130);
DISPLAY INVISIBLE (-6895 2130);
FORCEPROP 2 LAST PATH I403
J 0
(-6675 2300);
DISPLAY 0.680851 (-6675 2300);
DISPLAY INVISIBLE (-6675 2300);
FORCEADD OFFPAGE..2
(-6825 2150);
FORCEPROP 2 LAST $XR1 153 
J 0
(-6546 2150);
DISPLAY 0.638298 (-6546 2150);
PAINT MONO (-6546 2150);
FORCEPROP 2 LAST $XR0 29 
J 0
(-6636 2150);
DISPLAY 0.638298 (-6636 2150);
PAINT MONO (-6636 2150);
FORCEPROP 2 LAST CDS_LIB standard
J 2
(-6825 2150);
DISPLAY INVISIBLE (-6825 2150);
FORCEPROP 1 LAST OFFPAGE TRUE
J 0
(-6500 2025);
DISPLAY 0.872340 (-6500 2025);
PAINT GREEN (-6500 2025);
DISPLAY INVISIBLE (-6500 2025);
FORCEPROP 1 LAST COMMENT_BODY TRUE
J 0
(-6870 2055);
DISPLAY 0.872340 (-6870 2055);
PAINT PEACH (-6870 2055);
DISPLAY INVISIBLE (-6870 2055);
FORCEPROP 2 LAST PATH I404
J 0
(-6500 2200);
DISPLAY 0.680851 (-6500 2200);
DISPLAY INVISIBLE (-6500 2200);
FORCEADD Q_RES..1
(-7750 2150);
FORCEPROP 1 LAST LOCATION R458
J 0
(-7625 2150);
DISPLAY 0.489362 (-7625 2150);
PAINT SKYBLUE (-7625 2150);
FORCEPROP 0 LAST $SEC 1
J 0
(-7625 2200);
DISPLAY 0.680851 (-7625 2200);
PAINT MONO (-7625 2200);
DISPLAY INVISIBLE (-7625 2200);
FORCEPROP 0 LAST CDS_SEC 1
J 0
(-7625 2200);
DISPLAY 0.680851 (-7625 2200);
DISPLAY INVISIBLE (-7625 2200);
FORCEPROP 1 LASTPIN (-7850 2150) $PN 1
J 0
(-7838 2162);
DISPLAY 0.489362 (-7838 2162);
PAINT MONO (-7838 2162);
FORCEPROP 1 LASTPIN (-7650 2150) $PN 2
J 0
(-7688 2162);
DISPLAY 0.489362 (-7688 2162);
PAINT MONO (-7688 2162);
FORCEPROP 1 LAST MATERIAL EMPTY
J 0
(-7500 2150);
DISPLAY 0.489362 (-7500 2150);
PAINT SKYBLUE (-7500 2150);
FORCEPROP 1 LAST VALUE 30K
J 2
(-7850 2150);
DISPLAY 0.489362 (-7850 2150);
PAINT SKYBLUE (-7850 2150);
FORCEPROP 1 LAST PACK_TYPE 0402LF
J 0
(-7700 2075);
DISPLAY 0.489362 (-7700 2075);
PAINT SKYBLUE (-7700 2075);
DISPLAY INVISIBLE (-7700 2075);
FORCEPROP 1 LAST TOLERANCE 1%
J 0
(-7775 2075);
DISPLAY 0.489362 (-7775 2075);
PAINT SKYBLUE (-7775 2075);
DISPLAY INVISIBLE (-7775 2075);
FORCEPROP 1 LAST WATTAGE 1/16W
J 2
(-7350 2075);
DISPLAY 0.489362 (-7350 2075);
PAINT SKYBLUE (-7350 2075);
DISPLAY INVISIBLE (-7350 2075);
FORCEPROP 2 LAST CDS_LIB pure_quanta
J 0
(-7750 2150);
DISPLAY INVISIBLE (-7750 2150);
FORCEPROP 1 LAST PATH I405
J 0
(-7800 2300);
DISPLAY 0.978723 (-7800 2300);
PAINT WHITE (-7800 2300);
DISPLAY INVISIBLE (-7800 2300);
FORCEPROP 1 LAST PART_NUMBER CS33002FB02
J 0
(-7725 2200);
DISPLAY 0.489362 (-7725 2200);
PAINT SKYBLUE (-7725 2200);
DISPLAY INVISIBLE (-7725 2200);
FORCEADD Q_RES..1
(-6950 5900);
FORCEPROP 1 LAST LOCATION R459
J 0
(-6825 5900);
DISPLAY 0.489362 (-6825 5900);
PAINT SKYBLUE (-6825 5900);
FORCEPROP 0 LAST $SEC 1
J 0
(-6825 5925);
DISPLAY 0.680851 (-6825 5925);
PAINT MONO (-6825 5925);
DISPLAY INVISIBLE (-6825 5925);
FORCEPROP 0 LAST CDS_SEC 1
J 0
(-6825 5925);
DISPLAY 0.680851 (-6825 5925);
DISPLAY INVISIBLE (-6825 5925);
FORCEPROP 1 LASTPIN (-7050 5900) $PN 1
J 0
(-7038 5912);
DISPLAY 0.489362 (-7038 5912);
PAINT MONO (-7038 5912);
FORCEPROP 1 LASTPIN (-6850 5900) $PN 2
J 0
(-6888 5912);
DISPLAY 0.489362 (-6888 5912);
PAINT MONO (-6888 5912);
FORCEPROP 1 LAST VALUE 33
J 2
(-7050 5900);
DISPLAY 0.489362 (-7050 5900);
PAINT SKYBLUE (-7050 5900);
FORCEPROP 1 LAST PACK_TYPE 0402LF
J 0
(-6900 5825);
DISPLAY 0.489362 (-6900 5825);
PAINT SKYBLUE (-6900 5825);
DISPLAY INVISIBLE (-6900 5825);
FORCEPROP 1 LAST TOLERANCE 5%
J 0
(-6975 5825);
DISPLAY 0.489362 (-6975 5825);
PAINT SKYBLUE (-6975 5825);
DISPLAY INVISIBLE (-6975 5825);
FORCEPROP 1 LAST MATERIAL CHIP
J 0
(-6525 5825);
DISPLAY 0.489362 (-6525 5825);
PAINT SKYBLUE (-6525 5825);
DISPLAY INVISIBLE (-6525 5825);
FORCEPROP 1 LAST WATTAGE 1/16W
J 2
(-6550 5825);
DISPLAY 0.489362 (-6550 5825);
PAINT SKYBLUE (-6550 5825);
DISPLAY INVISIBLE (-6550 5825);
FORCEPROP 2 LAST CDS_LIB pure_quanta
J 0
(-6950 5900);
DISPLAY INVISIBLE (-6950 5900);
FORCEPROP 1 LAST PATH I407
J 0
(-7000 6050);
DISPLAY 0.978723 (-7000 6050);
PAINT WHITE (-7000 6050);
DISPLAY INVISIBLE (-7000 6050);
FORCEPROP 1 LAST PART_NUMBER CS03302JB10
J 0
(-6925 5950);
DISPLAY 0.489362 (-6925 5950);
PAINT SKYBLUE (-6925 5950);
DISPLAY INVISIBLE (-6925 5950);
FORCEADD Q_RES..1
(-6950 5850);
FORCEPROP 1 LAST LOCATION R460
J 0
(-6825 5850);
DISPLAY 0.489362 (-6825 5850);
PAINT SKYBLUE (-6825 5850);
FORCEPROP 0 LAST $SEC 1
J 0
(-6825 5875);
DISPLAY 0.680851 (-6825 5875);
PAINT MONO (-6825 5875);
DISPLAY INVISIBLE (-6825 5875);
FORCEPROP 0 LAST CDS_SEC 1
J 0
(-6825 5875);
DISPLAY 0.680851 (-6825 5875);
DISPLAY INVISIBLE (-6825 5875);
FORCEPROP 1 LASTPIN (-7050 5850) $PN 1
J 0
(-7038 5862);
DISPLAY 0.489362 (-7038 5862);
PAINT MONO (-7038 5862);
FORCEPROP 1 LASTPIN (-6850 5850) $PN 2
J 0
(-6888 5862);
DISPLAY 0.489362 (-6888 5862);
PAINT MONO (-6888 5862);
FORCEPROP 1 LAST VALUE 33
J 2
(-7050 5850);
DISPLAY 0.489362 (-7050 5850);
PAINT SKYBLUE (-7050 5850);
FORCEPROP 1 LAST WATTAGE 1/16W
J 2
(-6550 5775);
DISPLAY 0.489362 (-6550 5775);
PAINT SKYBLUE (-6550 5775);
DISPLAY INVISIBLE (-6550 5775);
FORCEPROP 1 LAST MATERIAL CHIP
J 0
(-6525 5775);
DISPLAY 0.489362 (-6525 5775);
PAINT SKYBLUE (-6525 5775);
DISPLAY INVISIBLE (-6525 5775);
FORCEPROP 1 LAST TOLERANCE 5%
J 0
(-6975 5775);
DISPLAY 0.489362 (-6975 5775);
PAINT SKYBLUE (-6975 5775);
DISPLAY INVISIBLE (-6975 5775);
FORCEPROP 1 LAST PACK_TYPE 0402LF
J 0
(-6900 5775);
DISPLAY 0.489362 (-6900 5775);
PAINT SKYBLUE (-6900 5775);
DISPLAY INVISIBLE (-6900 5775);
FORCEPROP 2 LAST CDS_LIB pure_quanta
J 0
(-6950 5850);
DISPLAY INVISIBLE (-6950 5850);
FORCEPROP 1 LAST PATH I408
J 0
(-7000 6000);
DISPLAY 0.978723 (-7000 6000);
PAINT WHITE (-7000 6000);
DISPLAY INVISIBLE (-7000 6000);
FORCEPROP 1 LAST PART_NUMBER CS03302JB10
J 0
(-6925 5900);
DISPLAY 0.489362 (-6925 5900);
PAINT SKYBLUE (-6925 5900);
DISPLAY INVISIBLE (-6925 5900);
FORCEADD Q_RES..1
(-6950 5650);
FORCEPROP 1 LAST LOCATION R461
J 0
(-6825 5650);
DISPLAY 0.489362 (-6825 5650);
PAINT SKYBLUE (-6825 5650);
FORCEPROP 0 LAST $SEC 1
J 0
(-6825 5675);
DISPLAY 0.680851 (-6825 5675);
PAINT MONO (-6825 5675);
DISPLAY INVISIBLE (-6825 5675);
FORCEPROP 0 LAST CDS_SEC 1
J 0
(-6825 5675);
DISPLAY 0.680851 (-6825 5675);
DISPLAY INVISIBLE (-6825 5675);
FORCEPROP 1 LASTPIN (-7050 5650) $PN 1
J 0
(-7038 5662);
DISPLAY 0.489362 (-7038 5662);
PAINT MONO (-7038 5662);
FORCEPROP 1 LASTPIN (-6850 5650) $PN 2
J 0
(-6888 5662);
DISPLAY 0.489362 (-6888 5662);
PAINT MONO (-6888 5662);
FORCEPROP 1 LAST VALUE 33
J 2
(-7050 5650);
DISPLAY 0.489362 (-7050 5650);
PAINT SKYBLUE (-7050 5650);
FORCEPROP 1 LAST PACK_TYPE 0402LF
J 0
(-6900 5575);
DISPLAY 0.489362 (-6900 5575);
PAINT SKYBLUE (-6900 5575);
DISPLAY INVISIBLE (-6900 5575);
FORCEPROP 1 LAST TOLERANCE 5%
J 0
(-6975 5575);
DISPLAY 0.489362 (-6975 5575);
PAINT SKYBLUE (-6975 5575);
DISPLAY INVISIBLE (-6975 5575);
FORCEPROP 1 LAST MATERIAL CHIP
J 0
(-6525 5575);
DISPLAY 0.489362 (-6525 5575);
PAINT SKYBLUE (-6525 5575);
DISPLAY INVISIBLE (-6525 5575);
FORCEPROP 1 LAST WATTAGE 1/16W
J 2
(-6550 5575);
DISPLAY 0.489362 (-6550 5575);
PAINT SKYBLUE (-6550 5575);
DISPLAY INVISIBLE (-6550 5575);
FORCEPROP 2 LAST CDS_LIB pure_quanta
J 0
(-6950 5650);
DISPLAY INVISIBLE (-6950 5650);
FORCEPROP 1 LAST PATH I409
J 0
(-7000 5800);
DISPLAY 0.978723 (-7000 5800);
PAINT WHITE (-7000 5800);
DISPLAY INVISIBLE (-7000 5800);
FORCEPROP 1 LAST PART_NUMBER CS03302JB10
J 0
(-6925 5700);
DISPLAY 0.489362 (-6925 5700);
PAINT SKYBLUE (-6925 5700);
DISPLAY INVISIBLE (-6925 5700);
FORCEADD Q_RES..1
(-6950 5250);
FORCEPROP 1 LAST LOCATION R464
J 0
(-6825 5250);
DISPLAY 0.489362 (-6825 5250);
PAINT SKYBLUE (-6825 5250);
FORCEPROP 0 LAST $SEC 1
J 0
(-6825 5275);
DISPLAY 0.680851 (-6825 5275);
PAINT MONO (-6825 5275);
DISPLAY INVISIBLE (-6825 5275);
FORCEPROP 0 LAST CDS_SEC 1
J 0
(-6825 5275);
DISPLAY 0.680851 (-6825 5275);
DISPLAY INVISIBLE (-6825 5275);
FORCEPROP 1 LASTPIN (-7050 5250) $PN 1
J 0
(-7038 5262);
DISPLAY 0.489362 (-7038 5262);
PAINT MONO (-7038 5262);
FORCEPROP 1 LASTPIN (-6850 5250) $PN 2
J 0
(-6888 5262);
DISPLAY 0.489362 (-6888 5262);
PAINT MONO (-6888 5262);
FORCEPROP 1 LAST VALUE 33
J 2
(-7050 5250);
DISPLAY 0.489362 (-7050 5250);
PAINT SKYBLUE (-7050 5250);
FORCEPROP 1 LAST PACK_TYPE 0402LF
J 0
(-6900 5175);
DISPLAY 0.489362 (-6900 5175);
PAINT SKYBLUE (-6900 5175);
DISPLAY INVISIBLE (-6900 5175);
FORCEPROP 1 LAST TOLERANCE 5%
J 0
(-6975 5175);
DISPLAY 0.489362 (-6975 5175);
PAINT SKYBLUE (-6975 5175);
DISPLAY INVISIBLE (-6975 5175);
FORCEPROP 1 LAST MATERIAL CHIP
J 0
(-6525 5175);
DISPLAY 0.489362 (-6525 5175);
PAINT SKYBLUE (-6525 5175);
DISPLAY INVISIBLE (-6525 5175);
FORCEPROP 1 LAST WATTAGE 1/16W
J 2
(-6550 5175);
DISPLAY 0.489362 (-6550 5175);
PAINT SKYBLUE (-6550 5175);
DISPLAY INVISIBLE (-6550 5175);
FORCEPROP 2 LAST CDS_LIB pure_quanta
J 0
(-6950 5250);
DISPLAY INVISIBLE (-6950 5250);
FORCEPROP 1 LAST PATH I410
J 0
(-7000 5400);
DISPLAY 0.978723 (-7000 5400);
PAINT WHITE (-7000 5400);
DISPLAY INVISIBLE (-7000 5400);
FORCEPROP 1 LAST PART_NUMBER CS03302JB10
J 0
(-6925 5300);
DISPLAY 0.489362 (-6925 5300);
PAINT SKYBLUE (-6925 5300);
DISPLAY INVISIBLE (-6925 5300);
FORCEADD Q_RES..1
(-6950 5200);
FORCEPROP 1 LAST LOCATION R465
J 0
(-6825 5200);
DISPLAY 0.489362 (-6825 5200);
PAINT SKYBLUE (-6825 5200);
FORCEPROP 0 LAST $SEC 1
J 0
(-6825 5225);
DISPLAY 0.680851 (-6825 5225);
PAINT MONO (-6825 5225);
DISPLAY INVISIBLE (-6825 5225);
FORCEPROP 0 LAST CDS_SEC 1
J 0
(-6825 5225);
DISPLAY 0.680851 (-6825 5225);
DISPLAY INVISIBLE (-6825 5225);
FORCEPROP 1 LASTPIN (-7050 5200) $PN 1
J 0
(-7038 5212);
DISPLAY 0.489362 (-7038 5212);
PAINT MONO (-7038 5212);
FORCEPROP 1 LASTPIN (-6850 5200) $PN 2
J 0
(-6888 5212);
DISPLAY 0.489362 (-6888 5212);
PAINT MONO (-6888 5212);
FORCEPROP 1 LAST VALUE 49.9
J 2
(-7050 5200);
DISPLAY 0.489362 (-7050 5200);
PAINT SKYBLUE (-7050 5200);
FORCEPROP 1 LAST TOLERANCE 1%
J 0
(-6975 5125);
DISPLAY 0.489362 (-6975 5125);
PAINT SKYBLUE (-6975 5125);
DISPLAY INVISIBLE (-6975 5125);
FORCEPROP 1 LAST PACK_TYPE 0402LF
J 0
(-6900 5125);
DISPLAY 0.489362 (-6900 5125);
PAINT SKYBLUE (-6900 5125);
DISPLAY INVISIBLE (-6900 5125);
FORCEPROP 1 LAST MATERIAL CHIP
J 0
(-6525 5125);
DISPLAY 0.489362 (-6525 5125);
PAINT SKYBLUE (-6525 5125);
DISPLAY INVISIBLE (-6525 5125);
FORCEPROP 1 LAST WATTAGE 1/16W
J 2
(-6550 5125);
DISPLAY 0.489362 (-6550 5125);
PAINT SKYBLUE (-6550 5125);
DISPLAY INVISIBLE (-6550 5125);
FORCEPROP 2 LAST CDS_LIB pure_quanta
J 0
(-6950 5200);
DISPLAY INVISIBLE (-6950 5200);
FORCEPROP 1 LAST PATH I411
J 0
(-7000 5350);
DISPLAY 0.978723 (-7000 5350);
PAINT WHITE (-7000 5350);
DISPLAY INVISIBLE (-7000 5350);
FORCEPROP 1 LAST PART_NUMBER CS04992FB07
J 0
(-6925 5250);
DISPLAY 0.489362 (-6925 5250);
PAINT SKYBLUE (-6925 5250);
DISPLAY INVISIBLE (-6925 5250);
FORCEADD Q_RES..1
(-6950 5150);
FORCEPROP 1 LAST LOCATION R466
J 0
(-6825 5150);
DISPLAY 0.489362 (-6825 5150);
PAINT SKYBLUE (-6825 5150);
FORCEPROP 0 LAST $SEC 1
J 0
(-6825 5175);
DISPLAY 0.680851 (-6825 5175);
PAINT MONO (-6825 5175);
DISPLAY INVISIBLE (-6825 5175);
FORCEPROP 0 LAST CDS_SEC 1
J 0
(-6825 5175);
DISPLAY 0.680851 (-6825 5175);
DISPLAY INVISIBLE (-6825 5175);
FORCEPROP 1 LASTPIN (-7050 5150) $PN 1
J 0
(-7038 5162);
DISPLAY 0.489362 (-7038 5162);
PAINT MONO (-7038 5162);
FORCEPROP 1 LASTPIN (-6850 5150) $PN 2
J 0
(-6888 5162);
DISPLAY 0.489362 (-6888 5162);
PAINT MONO (-6888 5162);
FORCEPROP 1 LAST VALUE 33
J 2
(-7050 5150);
DISPLAY 0.489362 (-7050 5150);
PAINT SKYBLUE (-7050 5150);
FORCEPROP 1 LAST PACK_TYPE 0402LF
J 0
(-6900 5075);
DISPLAY 0.489362 (-6900 5075);
PAINT SKYBLUE (-6900 5075);
DISPLAY INVISIBLE (-6900 5075);
FORCEPROP 1 LAST TOLERANCE 5%
J 0
(-6975 5075);
DISPLAY 0.489362 (-6975 5075);
PAINT SKYBLUE (-6975 5075);
DISPLAY INVISIBLE (-6975 5075);
FORCEPROP 1 LAST MATERIAL CHIP
J 0
(-6525 5075);
DISPLAY 0.489362 (-6525 5075);
PAINT SKYBLUE (-6525 5075);
DISPLAY INVISIBLE (-6525 5075);
FORCEPROP 1 LAST WATTAGE 1/16W
J 2
(-6550 5075);
DISPLAY 0.489362 (-6550 5075);
PAINT SKYBLUE (-6550 5075);
DISPLAY INVISIBLE (-6550 5075);
FORCEPROP 2 LAST CDS_LIB pure_quanta
J 0
(-6950 5150);
DISPLAY INVISIBLE (-6950 5150);
FORCEPROP 1 LAST PATH I412
J 0
(-7000 5300);
DISPLAY 0.978723 (-7000 5300);
PAINT WHITE (-7000 5300);
DISPLAY INVISIBLE (-7000 5300);
FORCEPROP 1 LAST PART_NUMBER CS03302JB10
J 0
(-6925 5200);
DISPLAY 0.489362 (-6925 5200);
PAINT SKYBLUE (-6925 5200);
DISPLAY INVISIBLE (-6925 5200);
FORCEADD Q_RES..1
(-6950 5100);
FORCEPROP 1 LAST LOCATION R467
J 0
(-6825 5100);
DISPLAY 0.489362 (-6825 5100);
PAINT SKYBLUE (-6825 5100);
FORCEPROP 0 LAST $SEC 1
J 0
(-6825 5125);
DISPLAY 0.680851 (-6825 5125);
PAINT MONO (-6825 5125);
DISPLAY INVISIBLE (-6825 5125);
FORCEPROP 0 LAST CDS_SEC 1
J 0
(-6825 5125);
DISPLAY 0.680851 (-6825 5125);
DISPLAY INVISIBLE (-6825 5125);
FORCEPROP 1 LASTPIN (-7050 5100) $PN 1
J 0
(-7038 5112);
DISPLAY 0.489362 (-7038 5112);
PAINT MONO (-7038 5112);
FORCEPROP 1 LASTPIN (-6850 5100) $PN 2
J 0
(-6888 5112);
DISPLAY 0.489362 (-6888 5112);
PAINT MONO (-6888 5112);
FORCEPROP 1 LAST VALUE 33
J 2
(-7050 5100);
DISPLAY 0.489362 (-7050 5100);
PAINT SKYBLUE (-7050 5100);
FORCEPROP 1 LAST PACK_TYPE 0402LF
J 0
(-6900 5025);
DISPLAY 0.489362 (-6900 5025);
PAINT SKYBLUE (-6900 5025);
DISPLAY INVISIBLE (-6900 5025);
FORCEPROP 1 LAST TOLERANCE 5%
J 0
(-6975 5025);
DISPLAY 0.489362 (-6975 5025);
PAINT SKYBLUE (-6975 5025);
DISPLAY INVISIBLE (-6975 5025);
FORCEPROP 1 LAST MATERIAL CHIP
J 0
(-6525 5025);
DISPLAY 0.489362 (-6525 5025);
PAINT SKYBLUE (-6525 5025);
DISPLAY INVISIBLE (-6525 5025);
FORCEPROP 1 LAST WATTAGE 1/16W
J 2
(-6550 5025);
DISPLAY 0.489362 (-6550 5025);
PAINT SKYBLUE (-6550 5025);
DISPLAY INVISIBLE (-6550 5025);
FORCEPROP 2 LAST CDS_LIB pure_quanta
J 0
(-6950 5100);
DISPLAY INVISIBLE (-6950 5100);
FORCEPROP 1 LAST PATH I413
J 0
(-7000 5250);
DISPLAY 0.978723 (-7000 5250);
PAINT WHITE (-7000 5250);
DISPLAY INVISIBLE (-7000 5250);
FORCEPROP 1 LAST PART_NUMBER CS03302JB10
J 0
(-6925 5150);
DISPLAY 0.489362 (-6925 5150);
PAINT SKYBLUE (-6925 5150);
DISPLAY INVISIBLE (-6925 5150);
FORCEADD Q_RES..1
(-6950 4250);
FORCEPROP 1 LAST LOCATION R475
J 0
(-6825 4250);
DISPLAY 0.489362 (-6825 4250);
PAINT SKYBLUE (-6825 4250);
FORCEPROP 0 LAST $SEC 1
J 0
(-6825 4275);
DISPLAY 0.680851 (-6825 4275);
PAINT MONO (-6825 4275);
DISPLAY INVISIBLE (-6825 4275);
FORCEPROP 0 LAST CDS_SEC 1
J 0
(-6825 4275);
DISPLAY 0.680851 (-6825 4275);
DISPLAY INVISIBLE (-6825 4275);
FORCEPROP 1 LASTPIN (-7050 4250) $PN 1
J 0
(-7038 4262);
DISPLAY 0.489362 (-7038 4262);
PAINT MONO (-7038 4262);
FORCEPROP 1 LASTPIN (-6850 4250) $PN 2
J 0
(-6888 4262);
DISPLAY 0.489362 (-6888 4262);
PAINT MONO (-6888 4262);
FORCEPROP 1 LAST VALUE 33
J 2
(-7050 4250);
DISPLAY 0.489362 (-7050 4250);
PAINT SKYBLUE (-7050 4250);
FORCEPROP 1 LAST PACK_TYPE 0402LF
J 0
(-6900 4175);
DISPLAY 0.489362 (-6900 4175);
PAINT SKYBLUE (-6900 4175);
DISPLAY INVISIBLE (-6900 4175);
FORCEPROP 1 LAST TOLERANCE 5%
J 0
(-6975 4175);
DISPLAY 0.489362 (-6975 4175);
PAINT SKYBLUE (-6975 4175);
DISPLAY INVISIBLE (-6975 4175);
FORCEPROP 1 LAST MATERIAL CHIP
J 0
(-6525 4175);
DISPLAY 0.489362 (-6525 4175);
PAINT SKYBLUE (-6525 4175);
DISPLAY INVISIBLE (-6525 4175);
FORCEPROP 1 LAST WATTAGE 1/16W
J 2
(-6550 4175);
DISPLAY 0.489362 (-6550 4175);
PAINT SKYBLUE (-6550 4175);
DISPLAY INVISIBLE (-6550 4175);
FORCEPROP 2 LAST CDS_LIB pure_quanta
J 0
(-6950 4250);
DISPLAY INVISIBLE (-6950 4250);
FORCEPROP 1 LAST PATH I414
J 0
(-7000 4400);
DISPLAY 0.978723 (-7000 4400);
PAINT WHITE (-7000 4400);
DISPLAY INVISIBLE (-7000 4400);
FORCEPROP 1 LAST PART_NUMBER CS03302JB10
J 0
(-6925 4300);
DISPLAY 0.489362 (-6925 4300);
PAINT SKYBLUE (-6925 4300);
DISPLAY INVISIBLE (-6925 4300);
FORCEADD OFFPAGE..2
(-1125 4550);
FORCEPROP 2 LAST $XR0 180 
J 0
(-936 4550);
DISPLAY 0.638298 (-936 4550);
PAINT MONO (-936 4550);
FORCEPROP 2 LAST CDS_LIB standard
J 0
(-1125 4550);
DISPLAY INVISIBLE (-1125 4550);
FORCEPROP 1 LAST OFFPAGE TRUE
J 0
(-800 4425);
DISPLAY 0.872340 (-800 4425);
PAINT GREEN (-800 4425);
DISPLAY INVISIBLE (-800 4425);
FORCEPROP 1 LAST COMMENT_BODY TRUE
J 0
(-1170 4455);
DISPLAY 0.872340 (-1170 4455);
PAINT GREEN (-1170 4455);
DISPLAY INVISIBLE (-1170 4455);
FORCEPROP 2 LAST PATH I419
J 0
(-950 4625);
DISPLAY 0.680851 (-950 4625);
DISPLAY INVISIBLE (-950 4625);
FORCEADD OFFPAGE..2
(-1125 4600);
FORCEPROP 2 LAST $XR0 180 
J 0
(-936 4600);
DISPLAY 0.638298 (-936 4600);
PAINT MONO (-936 4600);
FORCEPROP 2 LAST CDS_LIB standard
J 0
(-1125 4600);
DISPLAY INVISIBLE (-1125 4600);
FORCEPROP 1 LAST OFFPAGE TRUE
J 0
(-800 4475);
DISPLAY 0.872340 (-800 4475);
PAINT GREEN (-800 4475);
DISPLAY INVISIBLE (-800 4475);
FORCEPROP 1 LAST COMMENT_BODY TRUE
J 0
(-1170 4505);
DISPLAY 0.872340 (-1170 4505);
PAINT GREEN (-1170 4505);
DISPLAY INVISIBLE (-1170 4505);
FORCEPROP 2 LAST PATH I420
J 0
(-950 4675);
DISPLAY 0.680851 (-950 4675);
DISPLAY INVISIBLE (-950 4675);
FORCEADD OFFPAGE..4
(-1150 5250);
FORCEPROP 2 LAST $XR0 180 
J 0
(-964 5250);
DISPLAY 0.638298 (-964 5250);
PAINT MONO (-964 5250);
FORCEPROP 2 LAST CDS_LIB standard
J 0
(-1150 5250);
DISPLAY INVISIBLE (-1150 5250);
FORCEPROP 1 LAST OFFPAGE TRUE
J 0
(-825 5125);
DISPLAY 0.872340 (-825 5125);
DISPLAY INVISIBLE (-825 5125);
FORCEPROP 1 LAST COMMENT_BODY TRUE
J 0
(-1175 5150);
DISPLAY 0.872340 (-1175 5150);
PAINT GREEN (-1175 5150);
DISPLAY INVISIBLE (-1175 5150);
FORCEPROP 2 LAST PATH I421
J 0
(-975 5325);
DISPLAY 0.680851 (-975 5325);
DISPLAY INVISIBLE (-975 5325);
FORCEADD OFFPAGE..4
(-1150 5200);
FORCEPROP 2 LAST $XR0 180 
J 0
(-964 5200);
DISPLAY 0.638298 (-964 5200);
PAINT MONO (-964 5200);
FORCEPROP 2 LAST CDS_LIB standard
J 0
(-1150 5200);
DISPLAY INVISIBLE (-1150 5200);
FORCEPROP 1 LAST OFFPAGE TRUE
J 0
(-825 5075);
DISPLAY 0.872340 (-825 5075);
DISPLAY INVISIBLE (-825 5075);
FORCEPROP 1 LAST COMMENT_BODY TRUE
J 0
(-1175 5100);
DISPLAY 0.872340 (-1175 5100);
PAINT GREEN (-1175 5100);
DISPLAY INVISIBLE (-1175 5100);
FORCEPROP 2 LAST PATH I422
J 0
(-975 5275);
DISPLAY 0.680851 (-975 5275);
DISPLAY INVISIBLE (-975 5275);
FORCEADD OFFPAGE..3
(-2475 5450);
FORCEPROP 2 LAST $XR0 131 
J 0
(-2261 5450);
DISPLAY 0.638298 (-2261 5450);
PAINT MONO (-2261 5450);
FORCEPROP 2 LAST CDS_LIB standard
J 0
(-2475 5450);
DISPLAY INVISIBLE (-2475 5450);
FORCEPROP 1 LAST OFFPAGE TRUE
J 0
(-2150 5325);
DISPLAY 0.872340 (-2150 5325);
PAINT GREEN (-2150 5325);
DISPLAY INVISIBLE (-2150 5325);
FORCEPROP 1 LAST COMMENT_BODY TRUE
J 0
(-2525 5350);
DISPLAY 0.872340 (-2525 5350);
PAINT GREEN (-2525 5350);
DISPLAY INVISIBLE (-2525 5350);
FORCEPROP 2 LAST PATH I423
J 0
(-2275 5525);
DISPLAY 0.680851 (-2275 5525);
DISPLAY INVISIBLE (-2275 5525);
FORCEADD OFFPAGE..3
(-2475 5400);
FORCEPROP 2 LAST $XR0 131 
J 0
(-2261 5400);
DISPLAY 0.638298 (-2261 5400);
PAINT MONO (-2261 5400);
FORCEPROP 2 LAST CDS_LIB standard
J 0
(-2475 5400);
DISPLAY INVISIBLE (-2475 5400);
FORCEPROP 1 LAST OFFPAGE TRUE
J 0
(-2150 5275);
DISPLAY 0.872340 (-2150 5275);
PAINT GREEN (-2150 5275);
DISPLAY INVISIBLE (-2150 5275);
FORCEPROP 1 LAST COMMENT_BODY TRUE
J 0
(-2525 5300);
DISPLAY 0.872340 (-2525 5300);
PAINT GREEN (-2525 5300);
DISPLAY INVISIBLE (-2525 5300);
FORCEPROP 2 LAST PATH I424
J 0
(-2275 5475);
DISPLAY 0.680851 (-2275 5475);
DISPLAY INVISIBLE (-2275 5475);
FORCEADD Q_RES..1
(-6950 5550);
FORCEPROP 1 LAST LOCATION R462
J 0
(-6825 5550);
DISPLAY 0.489362 (-6825 5550);
PAINT SKYBLUE (-6825 5550);
FORCEPROP 0 LAST $SEC 1
J 0
(-6825 5575);
DISPLAY 0.680851 (-6825 5575);
PAINT MONO (-6825 5575);
DISPLAY INVISIBLE (-6825 5575);
FORCEPROP 0 LAST CDS_SEC 1
J 0
(-6825 5575);
DISPLAY 0.680851 (-6825 5575);
DISPLAY INVISIBLE (-6825 5575);
FORCEPROP 1 LASTPIN (-7050 5550) $PN 1
J 0
(-7038 5562);
DISPLAY 0.787234 (-7038 5562);
PAINT MONO (-7038 5562);
FORCEPROP 1 LASTPIN (-6850 5550) $PN 2
J 0
(-6888 5562);
DISPLAY 0.787234 (-6888 5562);
PAINT MONO (-6888 5562);
FORCEPROP 1 LAST MATERIAL EMPTY
J 0
(-7200 5550);
DISPLAY 0.489362 (-7200 5550);
PAINT RED (-7200 5550);
FORCEPROP 1 LAST VALUE 33
J 2
(-7050 5550);
DISPLAY 0.489362 (-7050 5550);
PAINT SKYBLUE (-7050 5550);
FORCEPROP 2 LAST CDS_LIB pure_quanta
J 0
(-6950 5550);
DISPLAY INVISIBLE (-6950 5550);
FORCEPROP 1 LAST PACK_TYPE 0402LF
J 0
(-6900 5475);
DISPLAY 0.489362 (-6900 5475);
PAINT SKYBLUE (-6900 5475);
DISPLAY INVISIBLE (-6900 5475);
FORCEPROP 1 LAST TOLERANCE 5%
J 0
(-6975 5475);
DISPLAY 0.489362 (-6975 5475);
PAINT SKYBLUE (-6975 5475);
DISPLAY INVISIBLE (-6975 5475);
FORCEPROP 1 LAST WATTAGE 1/16W
J 2
(-6550 5475);
DISPLAY 0.489362 (-6550 5475);
PAINT SKYBLUE (-6550 5475);
DISPLAY INVISIBLE (-6550 5475);
FORCEPROP 1 LAST PATH I425
J 0
(-7000 5700);
DISPLAY 0.978723 (-7000 5700);
PAINT WHITE (-7000 5700);
DISPLAY INVISIBLE (-7000 5700);
FORCEPROP 1 LAST PART_NUMBER CS03302JB10
J 0
(-6925 5600);
DISPLAY 0.489362 (-6925 5600);
PAINT SKYBLUE (-6925 5600);
DISPLAY INVISIBLE (-6925 5600);
FORCEADD Q_RES..1
(-6950 5600);
FORCEPROP 1 LAST LOCATION R1592
J 0
(-6825 5600);
DISPLAY 0.489362 (-6825 5600);
PAINT SKYBLUE (-6825 5600);
FORCEPROP 0 LAST $SEC 1
J 0
(-6825 5625);
DISPLAY 0.680851 (-6825 5625);
PAINT MONO (-6825 5625);
DISPLAY INVISIBLE (-6825 5625);
FORCEPROP 0 LAST CDS_SEC 1
J 0
(-6825 5625);
DISPLAY 0.680851 (-6825 5625);
DISPLAY INVISIBLE (-6825 5625);
FORCEPROP 1 LASTPIN (-7050 5600) $PN 1
J 0
(-7038 5612);
DISPLAY 0.787234 (-7038 5612);
PAINT MONO (-7038 5612);
FORCEPROP 1 LASTPIN (-6850 5600) $PN 2
J 0
(-6888 5612);
DISPLAY 0.787234 (-6888 5612);
PAINT MONO (-6888 5612);
FORCEPROP 1 LAST VALUE 33
J 2
(-7050 5600);
DISPLAY 0.489362 (-7050 5600);
PAINT SKYBLUE (-7050 5600);
FORCEPROP 2 LAST CDS_LIB pure_quanta
J 0
(-6950 5600);
DISPLAY INVISIBLE (-6950 5600);
FORCEPROP 1 LAST WATTAGE 1/16W
J 2
(-6550 5525);
DISPLAY 0.489362 (-6550 5525);
PAINT SKYBLUE (-6550 5525);
DISPLAY INVISIBLE (-6550 5525);
FORCEPROP 1 LAST MATERIAL CHIP
J 0
(-6525 5525);
DISPLAY 0.489362 (-6525 5525);
PAINT SKYBLUE (-6525 5525);
DISPLAY INVISIBLE (-6525 5525);
FORCEPROP 1 LAST TOLERANCE 5%
J 0
(-6975 5525);
DISPLAY 0.489362 (-6975 5525);
PAINT SKYBLUE (-6975 5525);
DISPLAY INVISIBLE (-6975 5525);
FORCEPROP 1 LAST PACK_TYPE 0402LF
J 0
(-6900 5525);
DISPLAY 0.489362 (-6900 5525);
PAINT SKYBLUE (-6900 5525);
DISPLAY INVISIBLE (-6900 5525);
FORCEPROP 1 LAST PATH I426
J 0
(-7000 5750);
DISPLAY 0.978723 (-7000 5750);
PAINT WHITE (-7000 5750);
DISPLAY INVISIBLE (-7000 5750);
FORCEPROP 1 LAST PART_NUMBER CS03302JB10
J 0
(-6925 5650);
DISPLAY 0.489362 (-6925 5650);
PAINT SKYBLUE (-6925 5650);
DISPLAY INVISIBLE (-6925 5650);
FORCEADD Q_RES..1
(-6950 4500);
FORCEPROP 1 LAST LOCATION R1593
J 0
(-6825 4500);
DISPLAY 0.489362 (-6825 4500);
PAINT SKYBLUE (-6825 4500);
FORCEPROP 0 LAST $SEC 1
J 0
(-6825 4525);
DISPLAY 0.680851 (-6825 4525);
PAINT MONO (-6825 4525);
DISPLAY INVISIBLE (-6825 4525);
FORCEPROP 0 LAST CDS_SEC 1
J 0
(-6825 4525);
DISPLAY 0.680851 (-6825 4525);
DISPLAY INVISIBLE (-6825 4525);
FORCEPROP 1 LASTPIN (-7050 4500) $PN 1
J 0
(-7038 4512);
DISPLAY 0.787234 (-7038 4512);
PAINT MONO (-7038 4512);
FORCEPROP 1 LASTPIN (-6850 4500) $PN 2
J 0
(-6888 4512);
DISPLAY 0.787234 (-6888 4512);
PAINT MONO (-6888 4512);
FORCEPROP 1 LAST VALUE 33
J 2
(-7050 4500);
DISPLAY 0.489362 (-7050 4500);
PAINT SKYBLUE (-7050 4500);
FORCEPROP 2 LAST CDS_LIB pure_quanta
J 0
(-6950 4500);
DISPLAY INVISIBLE (-6950 4500);
FORCEPROP 1 LAST WATTAGE 1/16W
J 2
(-6550 4425);
DISPLAY 0.489362 (-6550 4425);
PAINT SKYBLUE (-6550 4425);
DISPLAY INVISIBLE (-6550 4425);
FORCEPROP 1 LAST MATERIAL CHIP
J 0
(-6525 4425);
DISPLAY 0.489362 (-6525 4425);
PAINT SKYBLUE (-6525 4425);
DISPLAY INVISIBLE (-6525 4425);
FORCEPROP 1 LAST TOLERANCE 5%
J 0
(-6975 4425);
DISPLAY 0.489362 (-6975 4425);
PAINT SKYBLUE (-6975 4425);
DISPLAY INVISIBLE (-6975 4425);
FORCEPROP 1 LAST PACK_TYPE 0402LF
J 0
(-6900 4425);
DISPLAY 0.489362 (-6900 4425);
PAINT SKYBLUE (-6900 4425);
DISPLAY INVISIBLE (-6900 4425);
FORCEPROP 1 LAST PATH I427
J 0
(-7000 4650);
DISPLAY 0.978723 (-7000 4650);
PAINT WHITE (-7000 4650);
DISPLAY INVISIBLE (-7000 4650);
FORCEPROP 1 LAST PART_NUMBER CS03302JB10
J 0
(-6925 4550);
DISPLAY 0.489362 (-6925 4550);
PAINT SKYBLUE (-6925 4550);
DISPLAY INVISIBLE (-6925 4550);
FORCEADD Q_RES..1
(-6950 4650);
FORCEPROP 1 LAST LOCATION R472
J 0
(-6825 4650);
DISPLAY 0.489362 (-6825 4650);
PAINT SKYBLUE (-6825 4650);
FORCEPROP 0 LAST $SEC 1
J 0
(-6825 4675);
DISPLAY 0.680851 (-6825 4675);
PAINT MONO (-6825 4675);
DISPLAY INVISIBLE (-6825 4675);
FORCEPROP 0 LAST CDS_SEC 1
J 0
(-6825 4675);
DISPLAY 0.680851 (-6825 4675);
DISPLAY INVISIBLE (-6825 4675);
FORCEPROP 1 LASTPIN (-7050 4650) $PN 1
J 0
(-7038 4662);
DISPLAY 0.787234 (-7038 4662);
PAINT MONO (-7038 4662);
FORCEPROP 1 LASTPIN (-6850 4650) $PN 2
J 0
(-6888 4662);
DISPLAY 0.787234 (-6888 4662);
PAINT MONO (-6888 4662);
FORCEPROP 1 LAST VALUE 33
J 2
(-7050 4650);
DISPLAY 0.489362 (-7050 4650);
PAINT SKYBLUE (-7050 4650);
FORCEPROP 1 LAST MATERIAL EMPTY
J 0
(-7200 4650);
DISPLAY 0.489362 (-7200 4650);
PAINT RED (-7200 4650);
FORCEPROP 1 LAST WATTAGE 1/16W
J 2
(-6550 4575);
DISPLAY 0.489362 (-6550 4575);
PAINT SKYBLUE (-6550 4575);
DISPLAY INVISIBLE (-6550 4575);
FORCEPROP 1 LAST TOLERANCE 5%
J 0
(-6975 4575);
DISPLAY 0.489362 (-6975 4575);
PAINT SKYBLUE (-6975 4575);
DISPLAY INVISIBLE (-6975 4575);
FORCEPROP 1 LAST PACK_TYPE 0402LF
J 0
(-6900 4575);
DISPLAY 0.489362 (-6900 4575);
PAINT SKYBLUE (-6900 4575);
DISPLAY INVISIBLE (-6900 4575);
FORCEPROP 2 LAST CDS_LIB pure_quanta
J 0
(-6950 4650);
DISPLAY INVISIBLE (-6950 4650);
FORCEPROP 1 LAST PATH I428
J 0
(-7000 4800);
DISPLAY 0.978723 (-7000 4800);
PAINT WHITE (-7000 4800);
DISPLAY INVISIBLE (-7000 4800);
FORCEPROP 1 LAST PART_NUMBER CS03302JB10
J 0
(-6925 4700);
DISPLAY 0.489362 (-6925 4700);
PAINT SKYBLUE (-6925 4700);
DISPLAY INVISIBLE (-6925 4700);
FORCEADD OFFPAGE..2
R 2
(-7775 4650);
FORCEPROP 2 LAST $XR1 153 
J 0
(-8119 4650);
DISPLAY 0.638298 (-8119 4650);
PAINT MONO (-8119 4650);
FORCEPROP 2 LAST $XR0 29 
J 0
(-7999 4650);
DISPLAY 0.638298 (-7999 4650);
PAINT MONO (-7999 4650);
FORCEPROP 2 LAST CDS_LIB standard
J 0
(-7775 4650);
DISPLAY INVISIBLE (-7775 4650);
FORCEPROP 1 LAST OFFPAGE TRUE
J 2
(-8100 4525);
DISPLAY 0.872340 (-8100 4525);
PAINT GREEN (-8100 4525);
DISPLAY INVISIBLE (-8100 4525);
FORCEPROP 1 LAST COMMENT_BODY TRUE
J 2
(-7730 4555);
DISPLAY 0.872340 (-7730 4555);
PAINT PEACH (-7730 4555);
DISPLAY INVISIBLE (-7730 4555);
FORCEPROP 2 LAST PATH I429
J 0
(-7725 4725);
DISPLAY 0.680851 (-7725 4725);
DISPLAY INVISIBLE (-7725 4725);
FORCEADD Q_RES..1
(-6950 4450);
FORCEPROP 1 LAST LOCATION R473
J 0
(-6825 4450);
DISPLAY 0.489362 (-6825 4450);
PAINT SKYBLUE (-6825 4450);
FORCEPROP 0 LAST $SEC 1
J 0
(-6825 4475);
DISPLAY 0.680851 (-6825 4475);
PAINT MONO (-6825 4475);
DISPLAY INVISIBLE (-6825 4475);
FORCEPROP 0 LAST CDS_SEC 1
J 0
(-6825 4475);
DISPLAY 0.680851 (-6825 4475);
DISPLAY INVISIBLE (-6825 4475);
FORCEPROP 1 LASTPIN (-7050 4450) $PN 1
J 0
(-7038 4462);
DISPLAY 0.787234 (-7038 4462);
PAINT MONO (-7038 4462);
FORCEPROP 1 LASTPIN (-6850 4450) $PN 2
J 0
(-6888 4462);
DISPLAY 0.787234 (-6888 4462);
PAINT MONO (-6888 4462);
FORCEPROP 1 LAST VALUE 0
J 2
(-7050 4450);
DISPLAY 0.489362 (-7050 4450);
PAINT SKYBLUE (-7050 4450);
FORCEPROP 1 LAST WATTAGE 1/16W
J 2
(-6550 4375);
DISPLAY 0.489362 (-6550 4375);
PAINT SKYBLUE (-6550 4375);
DISPLAY INVISIBLE (-6550 4375);
FORCEPROP 1 LAST MATERIAL CHIP
J 0
(-6525 4375);
DISPLAY 0.489362 (-6525 4375);
PAINT SKYBLUE (-6525 4375);
DISPLAY INVISIBLE (-6525 4375);
FORCEPROP 1 LAST TOLERANCE 5%
J 0
(-6975 4375);
DISPLAY 0.489362 (-6975 4375);
PAINT SKYBLUE (-6975 4375);
DISPLAY INVISIBLE (-6975 4375);
FORCEPROP 1 LAST PACK_TYPE 0402LF
J 0
(-6900 4375);
DISPLAY 0.489362 (-6900 4375);
PAINT SKYBLUE (-6900 4375);
DISPLAY INVISIBLE (-6900 4375);
FORCEPROP 2 LAST CDS_LIB pure_quanta
J 0
(-6950 4450);
DISPLAY INVISIBLE (-6950 4450);
FORCEPROP 1 LAST PATH I430
J 0
(-7000 4600);
DISPLAY 0.978723 (-7000 4600);
PAINT WHITE (-7000 4600);
DISPLAY INVISIBLE (-7000 4600);
FORCEPROP 1 LAST PART_NUMBER CS00002JB13
J 0
(-6925 4500);
DISPLAY 0.489362 (-6925 4500);
PAINT SKYBLUE (-6925 4500);
DISPLAY INVISIBLE (-6925 4500);
FORCEADD DNS..2
(-6950 5500);
PAINT RED (-6950 5500);
FORCEPROP 2 LAST CDS_LIB mstr_misc
J 0
(-6950 5500);
DISPLAY INVISIBLE (-6950 5500);
FORCEPROP 1 LAST COMMENT_BODY TRUE
J 0
(-6950 5500);
PAINT RED (-6950 5500);
DISPLAY INVISIBLE (-6950 5500);
FORCEADD DNS..2
(-6975 4625);
PAINT RED (-6975 4625);
FORCEPROP 2 LAST CDS_LIB mstr_misc
J 0
(-6975 4625);
DISPLAY INVISIBLE (-6975 4625);
FORCEPROP 1 LAST COMMENT_BODY TRUE
J 0
(-6975 4625);
PAINT RED (-6975 4625);
DISPLAY INVISIBLE (-6975 4625);
FORCEADD DNS..2
(-7775 2100);
PAINT RED (-7775 2100);
FORCEPROP 2 LAST CDS_LIB mstr_misc
J 0
(-7775 2100);
DISPLAY INVISIBLE (-7775 2100);
FORCEPROP 1 LAST COMMENT_BODY TRUE
J 0
(-7775 2100);
PAINT RED (-7775 2100);
DISPLAY INVISIBLE (-7775 2100);
FORCEADD DNS..2
(-8000 3225);
PAINT RED (-8000 3225);
FORCEPROP 2 LAST CDS_LIB mstr_misc
J 0
(-8000 3225);
DISPLAY INVISIBLE (-8000 3225);
FORCEPROP 1 LAST COMMENT_BODY TRUE
J 0
(-8000 3225);
PAINT RED (-8000 3225);
DISPLAY INVISIBLE (-8000 3225);
FORCEADD DNS..2
(-8225 3225);
PAINT RED (-8225 3225);
FORCEPROP 2 LAST CDS_LIB mstr_misc
J 0
(-8225 3225);
DISPLAY INVISIBLE (-8225 3225);
FORCEPROP 1 LAST COMMENT_BODY TRUE
J 0
(-8225 3225);
PAINT RED (-8225 3225);
DISPLAY INVISIBLE (-8225 3225);
FORCEADD QUANTA_TITLE_BLOCK_C..1
(-100 100);
FORCEPROP 0 LAST CDS_CON_LAST_MODIFIED Thu Sep 14 16:11:53 2023
J 0
(-1985 115);
DISPLAY INVISIBLE (-1985 115);
FORCEPROP 1 LAST CUSTOM_TXT_CDS <CON_LAST_MODIFIED>
J 0
(-1985 115);
DISPLAY 0.978723 (-1985 115);
FORCEPROP 2 LAST CUSTOM_TXT_CDS <XR_PAGE_TITLE>
J 0
(-7990 5350);
DISPLAY 0.638298 (-7990 5350);
PAINT PINK (-7990 5350);
DISPLAY INVISIBLE (-7990 5350);
FORCEPROP 1 LAST CUSTOM_TXT_CDS <NAME_2>
J 0
(-3275 150);
FORCEPROP 1 LAST CUSTOM_TXT_CDS <NAME_1>
J 0
(-3275 275);
FORCEPROP 1 LAST CUSTOM_TXT_CDS <Q_NUMBER>
J 0
(-1503 203);
DISPLAY 1.212766 (-1503 203);
FORCEPROP 1 LAST CUSTOM_TXT_CDS <Q_PROJ>
J 0
(-2482 202);
DISPLAY 1.212766 (-2482 202);
FORCEPROP 1 LAST CUSTOM_TXT_CDS <Q_REV>
J 0
(-284 203);
DISPLAY 1.212766 (-284 203);
FORCEPROP 1 LAST CUSTOM_TXT_CDS <CON_PAGE_NUM> OF <CON_TOTAL_PAGES>
J 0
(-546 118);
DISPLAY 0.978723 (-546 118);
FORCEPROP 1 LAST Q_TITLE CPU0 SPI/USB
J 0
(-9400 150);
DISPLAY 2.446809 (-9400 150);
PAINT GREEN (-9400 150);
FORCEPROP 2 LAST PAGE_BORDER TRUE
J 0
(-7990 5350);
DISPLAY 0.638298 (-7990 5350);
PAINT PINK (-7990 5350);
DISPLAY INVISIBLE (-7990 5350);
FORCEPROP 1 LAST CDS_LMAN_SYM_OUTLINE -9475,6775,100,-125
J 0
(-100 100);
DISPLAY 0.468085 (-100 100);
PAINT GREEN (-100 100);
DISPLAY INVISIBLE (-100 100);
FORCEPROP 2 LAST CDS_LIB pure_quanta
J 0
(-100 100);
DISPLAY INVISIBLE (-100 100);
FORCEPROP 2 LAST CDS_XR_PAGE_TITLE CR-29 : @T6G_MB_LIB.T6G(SCH_1):PAGE29
J 0
(-7990 5350);
DISPLAY 0.638298 (-7990 5350);
PAINT PINK (-7990 5350);
DISPLAY INVISIBLE (-7990 5350);
FORCEPROP 1 LAST Q_DEPT BU9
J 1
(-3863 149);
DISPLAY 1.957447 (-3863 149);
PAINT GREEN (-3863 149);
DISPLAY INVISIBLE (-3863 149);
FORCEPROP 1 LAST COMMENT_BODY TRUE
J 0
(-88 87);
DISPLAY 0.978723 (-88 87);
PAINT GREEN (-88 87);
DISPLAY INVISIBLE (-88 87);
WIRE 16 -1 (-3725 2375)(-3725 2325);
WIRE 16 -1 (-2350 2675)(-2350 2800);
WIRE 16 -1 (-7725 4950)(-7050 4950);
FORCEPROP 2 LAST SIG_NAME ESPI_CPU0_D0
J 0
(-7610 4960);
DISPLAY 0.489362 (-7610 4960);
WIRE 16 -1 (-7725 4900)(-7050 4900);
FORCEPROP 2 LAST SIG_NAME ESPI_CPU0_D1
J 0
(-7610 4910);
DISPLAY 0.489362 (-7610 4910);
WIRE 16 -1 (-7050 4850)(-7725 4850);
FORCEPROP 2 LAST SIG_NAME ESPI_CPU0_D2
J 0
(-7610 4860);
DISPLAY 0.489362 (-7610 4860);
WIRE 16 -1 (-7050 4450)(-7725 4450);
FORCEPROP 2 LAST SIG_NAME CLK_ESPI_CPU0_CLK1
J 0
(-7610 4460);
DISPLAY 0.489362 (-7610 4460);
WIRE 16 -1 (-6850 4450)(-5925 4450);
FORCEPROP 2 LAST SIG_NAME CLK_ESPI_CPU0_R_CLK1
J 0
(-6685 4460);
DISPLAY 0.489362 (-6685 4460);
FORCEPROP 2 LASTPROP $XRERR UNIQUE?
J 0
(-6925 4460);
DISPLAY 0.638298 (-6925 4460);
PAINT MONO (-6925 4460);
DISPLAY INVISIBLE (-6925 4460);
WIRE 16 -1 (-7725 4400)(-5925 4400);
FORCEPROP 2 LAST SIG_NAME PD_ESPI_CPU0_CLK2
J 0
(-7610 4410);
DISPLAY 0.489362 (-7610 4410);
WIRE 16 -1 (-6850 4350)(-5925 4350);
FORCEPROP 2 LAST SIG_NAME RST_ESPI_CPU0_R_RSTOUT_N
J 0
(-6685 4360);
DISPLAY 0.489362 (-6685 4360);
FORCEPROP 2 LASTPROP $XRERR UNIQUE?
J 0
(-6925 4360);
DISPLAY 0.638298 (-6925 4360);
PAINT MONO (-6925 4360);
DISPLAY INVISIBLE (-6925 4360);
WIRE 16 -1 (-7050 4350)(-7725 4350);
FORCEPROP 2 LAST SIG_NAME RST_ESPI_CPU0_RSTOUT_N
J 0
(-7610 4360);
DISPLAY 0.489362 (-7610 4360);
WIRE 16 -1 (-7050 4250)(-7725 4250);
FORCEPROP 2 LAST SIG_NAME SPI_CPU0_TPM_CS_N
J 0
(-7610 4260);
DISPLAY 0.489362 (-7610 4260);
WIRE 16 -1 (-6850 4500)(-5925 4500);
FORCEPROP 2 LAST SIG_NAME CPU0_ESPI0_ALERT_N
J 0
(-6685 4510);
DISPLAY 0.489362 (-6685 4510);
FORCEPROP 2 LASTPROP $XRERR UNIQUE?
J 0
(-6925 4510);
DISPLAY 0.638298 (-6925 4510);
PAINT MONO (-6925 4510);
DISPLAY INVISIBLE (-6925 4510);
WIRE 16 -1 (-6850 4650)(-5925 4650);
FORCEPROP 2 LAST SIG_NAME ESPI_CPU0_R_ALERT_N
J 0
(-6685 4660);
DISPLAY 0.489362 (-6685 4660);
FORCEPROP 2 LASTPROP $XRERR UNIQUE?
J 0
(-6925 4660);
DISPLAY 0.638298 (-6925 4660);
PAINT MONO (-6925 4660);
DISPLAY INVISIBLE (-6925 4660);
WIRE 16 -1 (-6850 4800)(-5925 4800);
FORCEPROP 2 LAST SIG_NAME ESPI_CPU0_R_D3
J 0
(-6685 4810);
DISPLAY 0.489362 (-6685 4810);
FORCEPROP 2 LASTPROP $XRERR UNIQUE?
J 0
(-6925 4810);
DISPLAY 0.638298 (-6925 4810);
PAINT MONO (-6925 4810);
DISPLAY INVISIBLE (-6925 4810);
WIRE 16 -1 (-6850 4950)(-5925 4950);
FORCEPROP 2 LAST SIG_NAME ESPI_CPU0_R_D0
J 0
(-6685 4960);
DISPLAY 0.489362 (-6685 4960);
FORCEPROP 2 LASTPROP $XRERR UNIQUE?
J 0
(-6925 4960);
DISPLAY 0.638298 (-6925 4960);
PAINT MONO (-6925 4960);
DISPLAY INVISIBLE (-6925 4960);
WIRE 16 -1 (-6850 4900)(-5925 4900);
FORCEPROP 2 LAST SIG_NAME ESPI_CPU0_R_D1
J 0
(-6685 4910);
DISPLAY 0.489362 (-6685 4910);
FORCEPROP 2 LASTPROP $XRERR UNIQUE?
J 0
(-6925 4910);
DISPLAY 0.638298 (-6925 4910);
PAINT MONO (-6925 4910);
DISPLAY INVISIBLE (-6925 4910);
WIRE 16 -1 (-7050 4650)(-7200 4650);
WIRE 16 -1 (-7200 4500)(-7200 4650);
WIRE 16 -1 (-7200 4650)(-7725 4650);
FORCEPROP 2 LAST SIG_NAME ESPI_CPU0_ALERT_P0_N
J 0
(-7710 4660);
DISPLAY 0.489362 (-7710 4660);
WIRE 16 -1 (-7050 4500)(-7200 4500);
WIRE 16 -1 (-6875 2150)(-7650 2150);
FORCEPROP 2 LAST SIG_NAME ESPI_CPU0_ALERT_P0_N
J 0
(-7335 2160);
DISPLAY 0.489362 (-7335 2160);
WIRE 16 -1 (-6900 2775)(-8150 2775);
FORCEPROP 2 LAST SIG_NAME ESPI_CPU0_CS1_N
J 0
(-7535 2785);
DISPLAY 0.489362 (-7535 2785);
WIRE 16 -1 (-8150 3150)(-8150 2775);
WIRE 16 -1 (-6900 2225)(-7650 2225);
FORCEPROP 2 LAST SIG_NAME ESPI_CPU0_D3
J 0
(-7310 2235);
DISPLAY 0.489362 (-7310 2235);
WIRE 16 -1 (-6900 2275)(-7650 2275);
FORCEPROP 2 LAST SIG_NAME ESPI_CPU0_D2
J 0
(-7310 2285);
DISPLAY 0.489362 (-7310 2285);
WIRE 16 -1 (-7650 2325)(-6900 2325);
FORCEPROP 2 LAST SIG_NAME ESPI_CPU0_D1
J 0
(-7310 2335);
DISPLAY 0.489362 (-7310 2335);
WIRE 16 -1 (-6900 2875)(-7925 2875);
FORCEPROP 2 LAST SIG_NAME RST_ESPI_CPU0_RSTOUT_N
J 0
(-7535 2885);
DISPLAY 0.489362 (-7535 2885);
WIRE 16 -1 (-7925 3125)(-7925 2875);
WIRE 16 -1 (-8125 2575)(-8125 2375);
WIRE 16 -1 (-8125 2375)(-7850 2375);
WIRE 16 -1 (-8125 2325)(-8125 2375);
WIRE 16 -1 (-7850 2325)(-8125 2325);
WIRE 16 -1 (-8125 2275)(-8125 2325);
WIRE 16 -1 (-7850 2275)(-8125 2275);
WIRE 16 -1 (-8125 2225)(-8125 2275);
WIRE 16 -1 (-7850 2225)(-8125 2225);
WIRE 16 -1 (-8125 2225)(-8125 2150);
WIRE 16 -1 (-8125 2150)(-7850 2150);
WIRE 16 -1 (-7650 2375)(-6900 2375);
FORCEPROP 2 LAST SIG_NAME ESPI_CPU0_D0
J 0
(-7310 2385);
DISPLAY 0.489362 (-7310 2385);
WIRE 16 -1 (-7050 4800)(-7725 4800);
FORCEPROP 2 LAST SIG_NAME ESPI_CPU0_D3
J 0
(-7610 4810);
DISPLAY 0.489362 (-7610 4810);
WIRE 16 -1 (-6850 4850)(-5925 4850);
FORCEPROP 2 LAST SIG_NAME ESPI_CPU0_R_D2
J 0
(-6685 4860);
DISPLAY 0.489362 (-6685 4860);
FORCEPROP 2 LASTPROP $XRERR UNIQUE?
J 0
(-6925 4860);
DISPLAY 0.638298 (-6925 4860);
PAINT MONO (-6925 4860);
DISPLAY INVISIBLE (-6925 4860);
WIRE 16 -1 (-3550 2175)(-4550 2175);
FORCEPROP 2 LAST SIG_NAME SCM_USB_OC_N
J 2
(-4060 2185);
DISPLAY 0.489362 (-4060 2185);
WIRE 16 -1 (-3200 2175)(-2625 2175);
FORCEPROP 2 LAST SIG_NAME SCM_USB_OC_BU_R_N
J 0
(-3135 2185);
DISPLAY 0.489362 (-3135 2185);
FORCEPROP 2 LASTPROP $XRERR UNIQUE?
J 0
(-3375 2185);
DISPLAY 0.638298 (-3375 2185);
PAINT MONO (-3375 2185);
DISPLAY INVISIBLE (-3375 2185);
WIRE 16 -1 (-1675 2175)(-2350 2175);
FORCEPROP 2 LAST SIG_NAME SCM_USB_OC_BUF_N
J 0
(-2285 2185);
DISPLAY 0.489362 (-2285 2185);
WIRE 16 -1 (-2350 2475)(-2350 2175);
WIRE 16 -1 (-2350 2175)(-2425 2175);
WIRE 16 -1 (-3625 2075)(-3550 2075);
WIRE 16 -1 (-3625 2000)(-3625 2075);
WIRE 16 -1 (-3650 2275)(-3550 2275);
WIRE 16 -1 (-3650 2650)(-3650 2275);
WIRE 16 -1 (-3650 2700)(-3650 2650);
WIRE 16 -1 (-3725 2650)(-3650 2650);
WIRE 16 -1 (-3725 2575)(-3725 2650);
WIRE 16 -1 (-7050 5100)(-7725 5100);
FORCEPROP 2 LAST SIG_NAME SPI_CPU0_D3
J 0
(-7610 5110);
DISPLAY 0.489362 (-7610 5110);
WIRE 16 -1 (-6850 5100)(-5925 5100);
FORCEPROP 2 LAST SIG_NAME SPI_CPU0_R_D3
J 0
(-6685 5110);
DISPLAY 0.489362 (-6685 5110);
FORCEPROP 2 LASTPROP $XRERR UNIQUE?
J 0
(-6925 5110);
DISPLAY 0.638298 (-6925 5110);
PAINT MONO (-6925 5110);
DISPLAY INVISIBLE (-6925 5110);
WIRE 16 -1 (-8150 3350)(-8150 3525);
WIRE 16 -1 (-8150 3525)(-7925 3525);
WIRE 16 -1 (-7925 3525)(-7925 3625);
WIRE 16 -1 (-7925 3325)(-7925 3525);
WIRE 16 -1 (-7725 5450)(-5925 5450);
FORCEPROP 2 LAST SIG_NAME RST_CPU0_KBRST_R_N
J 0
(-6685 5460);
DISPLAY 0.489362 (-6685 5460);
WIRE 16 -1 (-6850 5600)(-5925 5600);
FORCEPROP 2 LAST SIG_NAME CPU0_ESPI_CS0_N
J 0
(-6685 5610);
DISPLAY 0.489362 (-6685 5610);
FORCEPROP 2 LASTPROP $XRERR UNIQUE?
J 0
(-6925 5610);
DISPLAY 0.638298 (-6925 5610);
PAINT MONO (-6925 5610);
DISPLAY INVISIBLE (-6925 5610);
WIRE 16 -1 (-6850 5650)(-5925 5650);
FORCEPROP 2 LAST SIG_NAME SPI_CPU0_R_CLK
J 0
(-6685 5660);
DISPLAY 0.489362 (-6685 5660);
FORCEPROP 2 LASTPROP $XRERR UNIQUE?
J 0
(-6925 5660);
DISPLAY 0.638298 (-6925 5660);
PAINT MONO (-6925 5660);
DISPLAY INVISIBLE (-6925 5660);
WIRE 16 -1 (-7725 5650)(-7050 5650);
FORCEPROP 2 LAST SIG_NAME SPI_CPU0_CLK
J 0
(-7610 5660);
DISPLAY 0.489362 (-7610 5660);
WIRE 16 -1 (-6850 5800)(-5925 5800);
FORCEPROP 2 LAST SIG_NAME NC_CPU0_SPI_CS2_N
J 0
(-6685 5810);
DISPLAY 0.489362 (-6685 5810);
FORCEPROP 2 LASTPROP $XRERR UNIQUE?
J 0
(-7090 5800);
DISPLAY 0.638298 (-7090 5800);
PAINT MONO (-7090 5800);
DISPLAY INVISIBLE (-7090 5800);
WIRE 16 -1 (-6850 5850)(-5925 5850);
FORCEPROP 2 LAST SIG_NAME SPI_CPU0_R_CS1_N
J 0
(-6685 5860);
DISPLAY 0.489362 (-6685 5860);
FORCEPROP 2 LASTPROP $XRERR UNIQUE?
J 0
(-6925 5860);
DISPLAY 0.638298 (-6925 5860);
PAINT MONO (-6925 5860);
DISPLAY INVISIBLE (-6925 5860);
WIRE 16 -1 (-6850 5150)(-5925 5150);
FORCEPROP 2 LAST SIG_NAME SPI_CPU0_R_D2
J 0
(-6685 5160);
DISPLAY 0.489362 (-6685 5160);
FORCEPROP 2 LASTPROP $XRERR UNIQUE?
J 0
(-6925 5160);
DISPLAY 0.638298 (-6925 5160);
PAINT MONO (-6925 5160);
DISPLAY INVISIBLE (-6925 5160);
WIRE 16 -1 (-6850 5200)(-5925 5200);
FORCEPROP 2 LAST SIG_NAME SPI_CPU0_R_D1
J 0
(-6685 5210);
DISPLAY 0.489362 (-6685 5210);
FORCEPROP 2 LASTPROP $XRERR UNIQUE?
J 0
(-6925 5210);
DISPLAY 0.638298 (-6925 5210);
PAINT MONO (-6925 5210);
DISPLAY INVISIBLE (-6925 5210);
WIRE 16 -1 (-6850 5250)(-5925 5250);
FORCEPROP 2 LAST SIG_NAME SPI_CPU0_R_D0
J 0
(-6685 5260);
DISPLAY 0.489362 (-6685 5260);
FORCEPROP 2 LASTPROP $XRERR UNIQUE?
J 0
(-6925 5260);
DISPLAY 0.638298 (-6925 5260);
PAINT MONO (-6925 5260);
DISPLAY INVISIBLE (-6925 5260);
WIRE 16 -1 (-6850 5550)(-5925 5550);
FORCEPROP 2 LAST SIG_NAME ESPI_CPU0_R_CS1_N
J 0
(-6685 5560);
DISPLAY 0.489362 (-6685 5560);
FORCEPROP 2 LASTPROP $XRERR UNIQUE?
J 0
(-6925 5560);
DISPLAY 0.638298 (-6925 5560);
PAINT MONO (-6925 5560);
DISPLAY INVISIBLE (-6925 5560);
WIRE 16 -1 (-7725 5550)(-7225 5550);
FORCEPROP 2 LAST SIG_NAME ESPI_CPU0_CS1_N
J 0
(-7610 5560);
DISPLAY 0.489362 (-7610 5560);
WIRE 16 -1 (-7225 5550)(-7050 5550);
WIRE 16 -1 (-7225 5600)(-7225 5550);
WIRE 16 -1 (-7050 5600)(-7225 5600);
WIRE 16 -1 (-7050 5850)(-7725 5850);
FORCEPROP 2 LAST SIG_NAME SPI_CPU0_CS1_N
J 0
(-7610 5860);
DISPLAY 0.489362 (-7610 5860);
WIRE 16 -1 (-7050 5900)(-7725 5900);
FORCEPROP 2 LAST SIG_NAME SPI_CPU0_CS0_N
J 0
(-7610 5910);
DISPLAY 0.489362 (-7610 5910);
WIRE 16 -1 (-3425 5550)(-2525 5550);
FORCEPROP 2 LAST SIG_NAME USB2_CPU0_P10_DN
J 0
(-3160 5560);
DISPLAY 0.489362 (-3160 5560);
WIRE 16 -1 (-1200 5250)(-3425 5250);
FORCEPROP 2 LAST SIG_NAME USB3_CPU0_BMC_RX_HUB_C_DP
J 0
(-1860 5260);
DISPLAY 0.553191 (-1860 5260);
PAINT WHITE (-1860 5260);
WIRE 16 -1 (-1200 5200)(-3425 5200);
FORCEPROP 2 LAST SIG_NAME USB3_CPU0_BMC_RX_HUB_C_DN
J 0
(-1860 5210);
DISPLAY 0.553191 (-1860 5210);
PAINT WHITE (-1860 5210);
WIRE 16 -1 (-3425 4600)(-1175 4600);
FORCEPROP 2 LAST SIG_NAME USB3_CPU0_BMC_TX_DP
J 0
(-3235 4610);
DISPLAY 0.553191 (-3235 4610);
PAINT WHITE (-3235 4610);
WIRE 16 -1 (-1175 4550)(-3425 4550);
FORCEPROP 2 LAST SIG_NAME USB3_CPU0_BMC_TX_DN
J 0
(-3235 4560);
DISPLAY 0.553191 (-3235 4560);
PAINT WHITE (-3235 4560);
WIRE 16 -1 (-1275 3950)(-3425 3950);
FORCEPROP 2 LAST SIG_NAME SCM_USB_OC_BUF_N
J 0
(-1760 3960);
DISPLAY 0.489362 (-1760 3960);
WIRE 16 -1 (-3425 5400)(-2525 5400);
FORCEPROP 2 LAST SIG_NAME USB2_CPU0_P11_DN
J 0
(-3160 5410);
DISPLAY 0.489362 (-3160 5410);
WIRE 16 -1 (-3425 5600)(-2525 5600);
FORCEPROP 2 LAST SIG_NAME USB2_CPU0_P10_DP
J 0
(-3160 5610);
DISPLAY 0.489362 (-3160 5610);
WIRE 16 -1 (-3425 5700)(-2525 5700);
FORCEPROP 2 LAST SIG_NAME USB2_CPU0_P1_DN
J 0
(-3160 5710);
DISPLAY 0.489362 (-3160 5710);
WIRE 16 -1 (-3425 5750)(-2525 5750);
FORCEPROP 2 LAST SIG_NAME USB2_CPU0_P1_DP
J 0
(-3160 5760);
DISPLAY 0.489362 (-3160 5760);
WIRE 16 -1 (-3425 5850)(-2525 5850);
FORCEPROP 2 LAST SIG_NAME USB2_CPU0_P0_DN
J 0
(-3160 5860);
DISPLAY 0.489362 (-3160 5860);
WIRE 16 -1 (-3425 5900)(-2525 5900);
FORCEPROP 2 LAST SIG_NAME USB2_CPU0_P0_DP
J 0
(-3160 5910);
DISPLAY 0.489362 (-3160 5910);
WIRE 16 -1 (-3425 5450)(-2525 5450);
FORCEPROP 2 LAST SIG_NAME USB2_CPU0_P11_DP
J 0
(-3160 5460);
DISPLAY 0.489362 (-3160 5460);
WIRE 16 -1 (-6850 4250)(-5925 4250);
FORCEPROP 2 LAST SIG_NAME SPI_CPU0_R_TPM_CS_N
J 0
(-6685 4260);
DISPLAY 0.489362 (-6685 4260);
FORCEPROP 2 LASTPROP $XRERR UNIQUE?
J 0
(-6925 4260);
DISPLAY 0.638298 (-6925 4260);
PAINT MONO (-6925 4260);
DISPLAY INVISIBLE (-6925 4260);
WIRE 16 -1 (-7050 5150)(-7725 5150);
FORCEPROP 2 LAST SIG_NAME SPI_CPU0_D2
J 0
(-7610 5160);
DISPLAY 0.489362 (-7610 5160);
WIRE 16 -1 (-7725 5250)(-7050 5250);
FORCEPROP 2 LAST SIG_NAME SPI_CPU0_D0
J 0
(-7610 5260);
DISPLAY 0.489362 (-7610 5260);
WIRE 16 -1 (-6850 5900)(-5925 5900);
FORCEPROP 2 LAST SIG_NAME SPI_CPU0_R_CS0_N
J 0
(-6685 5910);
DISPLAY 0.489362 (-6685 5910);
FORCEPROP 2 LASTPROP $XRERR UNIQUE?
J 0
(-6925 5910);
DISPLAY 0.638298 (-6925 5910);
PAINT MONO (-6925 5910);
DISPLAY INVISIBLE (-6925 5910);
WIRE 16 -1 (-7725 5200)(-7050 5200);
FORCEPROP 2 LAST SIG_NAME SPI_CPU0_D1
J 0
(-7610 5210);
DISPLAY 0.489362 (-7610 5210);
DOT 1 (-7225 5550);
CIRCLE (-2650 5500)(-2560 5500);
PAINT YELLOW (-2650 5500);
DOT 1 (-7925 3525);
DOT 1 (-7200 4650);
DOT 1 (-8125 2375);
DOT 1 (-8125 2325);
DOT 1 (-8125 2275);
DOT 1 (-8125 2225);
DOT 1 (-2350 2175);
DOT 1 (-3650 2650);
FORCENOTE
CAD NOTE: R472 R1593 CO-LAY
(-7350 4700) 0;
DISPLAY LEFT (-7350 4700);
DISPLAY 1.021277 (-7350 4700);
FORCENOTE
CAD NOTE: R462 R1592 CO-LAY
(-7350 5475) 0;
DISPLAY LEFT (-7350 5475);
DISPLAY 1.021277 (-7350 5475);
FORCENOTE
TO OCP SFF
(-2000 5400) 0;
DISPLAY LEFT (-2000 5400);
DISPLAY 1.021277 (-2000 5400);
FORCENOTE
TO DC-SCM
(-775 4550) 0;
DISPLAY LEFT (-775 4550);
DISPLAY 1.021277 (-775 4550);
FORCENOTE
FROM DC-SCM
(-800 5200) 0;
DISPLAY LEFT (-800 5200);
DISPLAY 1.021277 (-800 5200);
FORCENOTE
TBC
(-2700 5475) 0;
DISPLAY LEFT (-2700 5475);
DISPLAY 1.021277 (-2700 5475);
FORCENOTE
TO OCP V3_2
(-2000 5525) 0;
DISPLAY LEFT (-2000 5525);
DISPLAY 1.021277 (-2000 5525);
FORCENOTE
TO SCM BMC
(-2000 5725) 0;
DISPLAY LEFT (-2000 5725);
DISPLAY 1.021277 (-2000 5725);
FORCENOTE
TO SCM USB CONN
(-2000 5875) 0;
DISPLAY LEFT (-2000 5875);
DISPLAY 1.021277 (-2000 5875);
FORCENOTE
TBC
(-7400 3450) 0;
DISPLAY LEFT (-7400 3450);
DISPLAY 1.021277 (-7400 3450);
FORCENOTE
PU AT DC-SCM SIDE
(-7550 3250) 0;
DISPLAY LEFT (-7550 3250);
DISPLAY 1.021277 (-7550 3250);
QUIT
